G04 ================== begin FILE IDENTIFICATION RECORD ==================*
G04 Layout Name:  D:/<user>/Wistron_project/16315-1/gbr/16315-1.brd*
G04 Film Name:    SE_REF_L3*
G04 File Format:  Gerber RS274X*
G04 File Origin:  Cadence Allegro 16.5-S056*
G04 Origin Date:  Fri Jun 09 15:32:40 2017*
G04 *
G04 Layer:  BOARD GEOMETRY/SE_REF_L3_TBL*
G04 Layer:  BOARD GEOMETRY/SE_REF_L3_L3*
G04 Layer:  BOARD GEOMETRY/PANEL_OUTLINE*
G04 *
G04 Offset:    (0.00 0.00)*
G04 Mirror:    No*
G04 Mode:      Positive*
G04 Rotation:  0*
G04 FullContactRelief:  No*
G04 UndefLineWidth:     6.00*
G04 ================== end FILE IDENTIFICATION RECORD ====================*
%FSLAX35Y35*MOIN*%
%IR0*IPPOS*OFA0.00000B0.00000*MIA0B0*SFA1.00000B1.00000*%
%ADD10C,.02*%
%ADD11C,.006*%
%ADD12C,.00525*%
G75*
%LPD*%
G75*
G54D10*
G01X1985143Y1554618D02*
X2720143D01*
G01X1985143Y1623918D02*
Y1554618D01*
G01Y1589268D02*
X2720143D01*
G01X1985143Y1623918D02*
X2720143D01*
G01X2160143D02*
Y1554618D01*
G01X2405143Y1623918D02*
Y1554618D01*
G01X2510143Y1623918D02*
Y1554618D01*
G01X2720143Y1623918D02*
Y1554618D01*
G54D11*
G01X6250Y-185556D02*
Y-203056D01*
G01X1228Y-185556D02*
X11272D01*
G01X20038Y-203056D02*
Y-185556D01*
G01Y-194014D02*
X21130Y-192556D01*
X22222Y-191681D01*
X23968Y-191390D01*
X25278Y-191681D01*
X26807Y-192848D01*
X27462Y-194598D01*
Y-203056D01*
G01X41250Y-191390D02*
Y-203056D01*
G01Y-186723D02*
X40813Y-186431D01*
Y-185848D01*
X41250Y-185556D01*
X41687Y-185848D01*
Y-186431D01*
X41250Y-186723D01*
G01X55475Y-201015D02*
X56567Y-202181D01*
X58095Y-203056D01*
X59405D01*
X60715Y-202473D01*
X61588Y-201598D01*
X62025Y-200432D01*
X61807Y-198681D01*
X60933Y-197806D01*
X57003Y-196056D01*
X56130Y-194014D01*
X56567Y-192556D01*
X57440Y-191681D01*
X58750Y-191390D01*
X60060Y-191681D01*
X61370Y-192556D01*
G01X90693Y-207431D02*
X92222Y-208598D01*
X93968Y-208889D01*
X95496Y-208598D01*
X96807Y-207140D01*
X97680Y-205098D01*
Y-191390D01*
G01Y-193723D02*
X96807Y-192556D01*
X95496Y-191681D01*
X93968Y-191390D01*
X92222Y-191973D01*
X91130Y-193139D01*
X90256Y-195181D01*
X89820Y-197223D01*
X90038Y-198973D01*
X90912Y-201015D01*
X92222Y-202473D01*
X93968Y-203056D01*
X95278Y-202764D01*
X96807Y-201598D01*
X97680Y-200432D01*
G01X107975Y-195181D02*
X114962D01*
X114307Y-193139D01*
X113215Y-191973D01*
X111687Y-191390D01*
X110158Y-191681D01*
X108848Y-192556D01*
X107975Y-194598D01*
X107538Y-196348D01*
Y-198098D01*
X107975Y-199848D01*
X109067Y-201598D01*
X110377Y-202764D01*
X111905Y-203056D01*
X113433Y-202473D01*
X114962Y-200723D01*
G01X125693Y-203056D02*
Y-191390D01*
G01Y-193723D02*
X126785Y-192556D01*
X127877Y-191681D01*
X129405Y-191390D01*
X130496Y-191681D01*
X131807Y-192556D01*
G01X142320Y-203056D02*
Y-185556D01*
G01Y-194306D02*
X143412Y-192556D01*
X144722Y-191681D01*
X146032Y-191390D01*
X147996Y-191973D01*
X149307Y-193139D01*
X150180Y-195181D01*
Y-197514D01*
X149743Y-199848D01*
X148870Y-201598D01*
X147342Y-202764D01*
X146032Y-203056D01*
X144722Y-202764D01*
X143412Y-201890D01*
X142320Y-200432D01*
G01X160475Y-195181D02*
X167462D01*
X166807Y-193139D01*
X165715Y-191973D01*
X164187Y-191390D01*
X162658Y-191681D01*
X161348Y-192556D01*
X160475Y-194598D01*
X160038Y-196348D01*
Y-198098D01*
X160475Y-199848D01*
X161567Y-201598D01*
X162877Y-202764D01*
X164405Y-203056D01*
X165933Y-202473D01*
X167462Y-200723D01*
G01X178193Y-203056D02*
Y-191390D01*
G01Y-193723D02*
X179285Y-192556D01*
X180377Y-191681D01*
X181905Y-191390D01*
X182996Y-191681D01*
X184307Y-192556D01*
G01X216250Y-191390D02*
Y-203056D01*
G01Y-186723D02*
X215813Y-186431D01*
Y-185848D01*
X216250Y-185556D01*
X216687Y-185848D01*
Y-186431D01*
X216250Y-186723D01*
G01X230475Y-201015D02*
X231567Y-202181D01*
X233095Y-203056D01*
X234405D01*
X235715Y-202473D01*
X236588Y-201598D01*
X237025Y-200432D01*
X236807Y-198681D01*
X235933Y-197806D01*
X232003Y-196056D01*
X231130Y-194014D01*
X231567Y-192556D01*
X232440Y-191681D01*
X233750Y-191390D01*
X235060Y-191681D01*
X236370Y-192556D01*
G01X265256Y-207431D02*
X266785Y-208598D01*
X268095Y-208889D01*
X269842Y-208306D01*
X271152Y-206848D01*
X271807Y-204222D01*
Y-191390D01*
G01Y-186723D02*
X271370Y-186431D01*
Y-185848D01*
X271807Y-185556D01*
X272243Y-185848D01*
Y-186431D01*
X271807Y-186723D01*
G01X282538Y-191390D02*
Y-199556D01*
X283412Y-201598D01*
X284722Y-202764D01*
X286250Y-203056D01*
X287778Y-202764D01*
X289088Y-201598D01*
X289962Y-199556D01*
G01Y-203056D02*
Y-191390D01*
G01X300475Y-201015D02*
X301567Y-202181D01*
X303095Y-203056D01*
X304405D01*
X305715Y-202473D01*
X306588Y-201598D01*
X307025Y-200432D01*
X306807Y-198681D01*
X305933Y-197806D01*
X302003Y-196056D01*
X301130Y-194014D01*
X301567Y-192556D01*
X302440Y-191681D01*
X303750Y-191390D01*
X305060Y-191681D01*
X306370Y-192556D01*
G01X321250Y-185556D02*
Y-203056D01*
G01X318193Y-191390D02*
X324307D01*
G01X354940Y-203056D02*
Y-188181D01*
X355377Y-186723D01*
X356250Y-185848D01*
X357560Y-185556D01*
X358870Y-186139D01*
X359525Y-187598D01*
G01X356905Y-192556D02*
X352538D01*
G01X373750Y-203056D02*
X372440Y-202764D01*
X371130Y-201598D01*
X370256Y-199556D01*
X369820Y-197223D01*
X370256Y-194889D01*
X371130Y-192848D01*
X372440Y-191681D01*
X373750Y-191390D01*
X375060Y-191681D01*
X376370Y-192848D01*
X377243Y-194889D01*
X377462Y-197223D01*
X377243Y-199556D01*
X376370Y-201598D01*
X375060Y-202764D01*
X373750Y-203056D01*
G01X388193D02*
Y-191390D01*
G01Y-193723D02*
X389285Y-192556D01*
X390377Y-191681D01*
X391905Y-191390D01*
X392996Y-191681D01*
X394307Y-192556D01*
G01X421665Y-208306D02*
X422975Y-208889D01*
X424722Y-208306D01*
X425813Y-207140D01*
X426687Y-205681D01*
X427996Y-201015D01*
X430835Y-191390D01*
G01X423848D02*
X427996Y-201015D01*
G01X443750Y-203056D02*
X442440Y-202764D01*
X441130Y-201598D01*
X440256Y-199556D01*
X439820Y-197223D01*
X440256Y-194889D01*
X441130Y-192848D01*
X442440Y-191681D01*
X443750Y-191390D01*
X445060Y-191681D01*
X446370Y-192848D01*
X447243Y-194889D01*
X447462Y-197223D01*
X447243Y-199556D01*
X446370Y-201598D01*
X445060Y-202764D01*
X443750Y-203056D01*
G01X457538Y-191390D02*
Y-199556D01*
X458412Y-201598D01*
X459722Y-202764D01*
X461250Y-203056D01*
X462778Y-202764D01*
X464088Y-201598D01*
X464962Y-199556D01*
G01Y-203056D02*
Y-191390D01*
G01X475693Y-203056D02*
Y-191390D01*
G01Y-193723D02*
X476785Y-192556D01*
X477877Y-191681D01*
X479405Y-191390D01*
X480496Y-191681D01*
X481807Y-192556D01*
G01X510693Y-203056D02*
Y-191390D01*
G01Y-193723D02*
X511785Y-192556D01*
X512877Y-191681D01*
X514405Y-191390D01*
X515496Y-191681D01*
X516807Y-192556D01*
G01X527975Y-195181D02*
X534962D01*
X534307Y-193139D01*
X533215Y-191973D01*
X531687Y-191390D01*
X530158Y-191681D01*
X528848Y-192556D01*
X527975Y-194598D01*
X527538Y-196348D01*
Y-198098D01*
X527975Y-199848D01*
X529067Y-201598D01*
X530377Y-202764D01*
X531905Y-203056D01*
X533433Y-202473D01*
X534962Y-200723D01*
G01X547440Y-203056D02*
Y-188181D01*
X547877Y-186723D01*
X548750Y-185848D01*
X550060Y-185556D01*
X551370Y-186139D01*
X552025Y-187598D01*
G01X549405Y-192556D02*
X545038D01*
G01X562975Y-195181D02*
X569962D01*
X569307Y-193139D01*
X568215Y-191973D01*
X566687Y-191390D01*
X565158Y-191681D01*
X563848Y-192556D01*
X562975Y-194598D01*
X562538Y-196348D01*
Y-198098D01*
X562975Y-199848D01*
X564067Y-201598D01*
X565377Y-202764D01*
X566905Y-203056D01*
X568433Y-202473D01*
X569962Y-200723D01*
G01X580693Y-203056D02*
Y-191390D01*
G01Y-193723D02*
X581785Y-192556D01*
X582877Y-191681D01*
X584405Y-191390D01*
X585496Y-191681D01*
X586807Y-192556D01*
G01X597975Y-195181D02*
X604962D01*
X604307Y-193139D01*
X603215Y-191973D01*
X601687Y-191390D01*
X600158Y-191681D01*
X598848Y-192556D01*
X597975Y-194598D01*
X597538Y-196348D01*
Y-198098D01*
X597975Y-199848D01*
X599067Y-201598D01*
X600377Y-202764D01*
X601905Y-203056D01*
X603433Y-202473D01*
X604962Y-200723D01*
G01X615038Y-203056D02*
Y-191390D01*
G01Y-194306D02*
X615912Y-192848D01*
X617222Y-191681D01*
X618968Y-191390D01*
X620496Y-191681D01*
X621807Y-192848D01*
X622462Y-194889D01*
Y-203056D01*
G01X639743Y-192848D02*
X638215Y-191681D01*
X636905Y-191390D01*
X635158Y-191973D01*
X633848Y-193139D01*
X632975Y-195181D01*
X632756Y-197223D01*
X632975Y-199265D01*
X633848Y-201015D01*
X635158Y-202473D01*
X636905Y-203056D01*
X638433Y-202473D01*
X639743Y-201306D01*
G01X650475Y-195181D02*
X657462D01*
X656807Y-193139D01*
X655715Y-191973D01*
X654187Y-191390D01*
X652658Y-191681D01*
X651348Y-192556D01*
X650475Y-194598D01*
X650038Y-196348D01*
Y-198098D01*
X650475Y-199848D01*
X651567Y-201598D01*
X652877Y-202764D01*
X654405Y-203056D01*
X655933Y-202473D01*
X657462Y-200723D01*
G01X688750Y-185556D02*
Y-203056D01*
G01X685693Y-191390D02*
X691807D01*
G01X706250Y-203056D02*
X704940Y-202764D01*
X703630Y-201598D01*
X702756Y-199556D01*
X702320Y-197223D01*
X702756Y-194889D01*
X703630Y-192848D01*
X704940Y-191681D01*
X706250Y-191390D01*
X707560Y-191681D01*
X708870Y-192848D01*
X709743Y-194889D01*
X709962Y-197223D01*
X709743Y-199556D01*
X708870Y-201598D01*
X707560Y-202764D01*
X706250Y-203056D01*
G01X739940D02*
Y-188181D01*
X740377Y-186723D01*
X741250Y-185848D01*
X742560Y-185556D01*
X743870Y-186139D01*
X744525Y-187598D01*
G01X741905Y-192556D02*
X737538D01*
G01X758750Y-191390D02*
Y-203056D01*
G01Y-186723D02*
X758313Y-186431D01*
Y-185848D01*
X758750Y-185556D01*
X759187Y-185848D01*
Y-186431D01*
X758750Y-186723D01*
G01X772538Y-203056D02*
Y-191390D01*
G01Y-194306D02*
X773412Y-192848D01*
X774722Y-191681D01*
X776468Y-191390D01*
X777996Y-191681D01*
X779307Y-192848D01*
X779962Y-194889D01*
Y-203056D01*
G01X797680Y-185556D02*
Y-203056D01*
G01Y-200432D02*
X796807Y-201890D01*
X795496Y-202764D01*
X793968Y-203056D01*
X792222Y-202473D01*
X790912Y-201015D01*
X790038Y-199265D01*
X789820Y-197223D01*
X790038Y-195181D01*
X790912Y-193431D01*
X792222Y-191973D01*
X793968Y-191390D01*
X795496Y-191681D01*
X796588Y-192265D01*
X797680Y-193431D01*
G01X828750Y-185556D02*
Y-203056D01*
G01X825693Y-191390D02*
X831807D01*
G01X842538Y-203056D02*
Y-185556D01*
G01Y-194014D02*
X843630Y-192556D01*
X844722Y-191681D01*
X846468Y-191390D01*
X847778Y-191681D01*
X849307Y-192848D01*
X849962Y-194598D01*
Y-203056D01*
G01X860475Y-195181D02*
X867462D01*
X866807Y-193139D01*
X865715Y-191973D01*
X864187Y-191390D01*
X862658Y-191681D01*
X861348Y-192556D01*
X860475Y-194598D01*
X860038Y-196348D01*
Y-198098D01*
X860475Y-199848D01*
X861567Y-201598D01*
X862877Y-202764D01*
X864405Y-203056D01*
X865933Y-202473D01*
X867462Y-200723D01*
G01X894165D02*
X895912Y-202181D01*
X897877Y-203056D01*
X899623D01*
X901370Y-202181D01*
X902680Y-200723D01*
X903335Y-198681D01*
X902898Y-196640D01*
X901807Y-194889D01*
X899842Y-193723D01*
X897222Y-193139D01*
X895693Y-191973D01*
X895038Y-189931D01*
X895475Y-187889D01*
X896567Y-186431D01*
X898095Y-185556D01*
X899623D01*
X901152Y-186139D01*
X902462Y-187598D01*
G01X920617Y-203056D02*
X911883D01*
Y-185556D01*
X920617D01*
G01X917123Y-194014D02*
X911883D01*
G01X951250Y-191390D02*
Y-203056D01*
G01Y-186723D02*
X950813Y-186431D01*
Y-185848D01*
X951250Y-185556D01*
X951687Y-185848D01*
Y-186431D01*
X951250Y-186723D01*
G01X962200Y-203056D02*
Y-191390D01*
G01Y-194598D02*
X962855Y-193139D01*
X963947Y-191973D01*
X965475Y-191390D01*
X967003Y-191973D01*
X968095Y-193139D01*
X968750Y-194598D01*
Y-203056D01*
G01Y-194598D02*
X969405Y-193139D01*
X970496Y-191973D01*
X972025Y-191390D01*
X973553Y-191973D01*
X974645Y-193139D01*
X975300Y-194889D01*
Y-203056D01*
G01X982320Y-208889D02*
Y-191390D01*
G01Y-194014D02*
X983412Y-192556D01*
X984503Y-191681D01*
X986250Y-191390D01*
X987778Y-191681D01*
X989307Y-193139D01*
X989962Y-195181D01*
X990180Y-197223D01*
X989962Y-199265D01*
X989307Y-201306D01*
X987996Y-202473D01*
X986250Y-203056D01*
X984722Y-202764D01*
X983193Y-201890D01*
X982320Y-200723D01*
G01X1000475Y-195181D02*
X1007462D01*
X1006807Y-193139D01*
X1005715Y-191973D01*
X1004187Y-191390D01*
X1002658Y-191681D01*
X1001348Y-192556D01*
X1000475Y-194598D01*
X1000038Y-196348D01*
Y-198098D01*
X1000475Y-199848D01*
X1001567Y-201598D01*
X1002877Y-202764D01*
X1004405Y-203056D01*
X1005933Y-202473D01*
X1007462Y-200723D01*
G01X1025180Y-185556D02*
Y-203056D01*
G01Y-200432D02*
X1024307Y-201890D01*
X1022996Y-202764D01*
X1021468Y-203056D01*
X1019722Y-202473D01*
X1018412Y-201015D01*
X1017538Y-199265D01*
X1017320Y-197223D01*
X1017538Y-195181D01*
X1018412Y-193431D01*
X1019722Y-191973D01*
X1021468Y-191390D01*
X1022996Y-191681D01*
X1024088Y-192265D01*
X1025180Y-193431D01*
G01X1042680Y-203056D02*
Y-191390D01*
G01Y-193431D02*
X1041807Y-192265D01*
X1040496Y-191681D01*
X1038968Y-191390D01*
X1037440Y-191973D01*
X1036130Y-193139D01*
X1035256Y-194889D01*
X1034820Y-197223D01*
X1035256Y-199556D01*
X1036130Y-201306D01*
X1037440Y-202473D01*
X1038968Y-203056D01*
X1040496Y-202764D01*
X1041807Y-201890D01*
X1042680Y-200723D01*
G01X1052538Y-203056D02*
Y-191390D01*
G01Y-194306D02*
X1053412Y-192848D01*
X1054722Y-191681D01*
X1056468Y-191390D01*
X1057996Y-191681D01*
X1059307Y-192848D01*
X1059962Y-194889D01*
Y-203056D01*
G01X1077243Y-192848D02*
X1075715Y-191681D01*
X1074405Y-191390D01*
X1072658Y-191973D01*
X1071348Y-193139D01*
X1070475Y-195181D01*
X1070256Y-197223D01*
X1070475Y-199265D01*
X1071348Y-201015D01*
X1072658Y-202473D01*
X1074405Y-203056D01*
X1075933Y-202473D01*
X1077243Y-201306D01*
G01X1087975Y-195181D02*
X1094962D01*
X1094307Y-193139D01*
X1093215Y-191973D01*
X1091687Y-191390D01*
X1090158Y-191681D01*
X1088848Y-192556D01*
X1087975Y-194598D01*
X1087538Y-196348D01*
Y-198098D01*
X1087975Y-199848D01*
X1089067Y-201598D01*
X1090377Y-202764D01*
X1091905Y-203056D01*
X1093433Y-202473D01*
X1094962Y-200723D01*
G01X1126250Y-185556D02*
Y-203056D01*
G01X1123193Y-191390D02*
X1129307D01*
G01X1140693Y-203056D02*
Y-191390D01*
G01Y-193723D02*
X1141785Y-192556D01*
X1142877Y-191681D01*
X1144405Y-191390D01*
X1145496Y-191681D01*
X1146807Y-192556D01*
G01X1165180Y-203056D02*
Y-191390D01*
G01Y-193431D02*
X1164307Y-192265D01*
X1162996Y-191681D01*
X1161468Y-191390D01*
X1159940Y-191973D01*
X1158630Y-193139D01*
X1157756Y-194889D01*
X1157320Y-197223D01*
X1157756Y-199556D01*
X1158630Y-201306D01*
X1159940Y-202473D01*
X1161468Y-203056D01*
X1162996Y-202764D01*
X1164307Y-201890D01*
X1165180Y-200723D01*
G01X1182243Y-192848D02*
X1180715Y-191681D01*
X1179405Y-191390D01*
X1177658Y-191973D01*
X1176348Y-193139D01*
X1175475Y-195181D01*
X1175256Y-197223D01*
X1175475Y-199265D01*
X1176348Y-201015D01*
X1177658Y-202473D01*
X1179405Y-203056D01*
X1180933Y-202473D01*
X1182243Y-201306D01*
G01X1192975Y-195181D02*
X1199962D01*
X1199307Y-193139D01*
X1198215Y-191973D01*
X1196687Y-191390D01*
X1195158Y-191681D01*
X1193848Y-192556D01*
X1192975Y-194598D01*
X1192538Y-196348D01*
Y-198098D01*
X1192975Y-199848D01*
X1194067Y-201598D01*
X1195377Y-202764D01*
X1196905Y-203056D01*
X1198433Y-202473D01*
X1199962Y-200723D01*
G01X1210475Y-201015D02*
X1211567Y-202181D01*
X1213095Y-203056D01*
X1214405D01*
X1215715Y-202473D01*
X1216588Y-201598D01*
X1217025Y-200432D01*
X1216807Y-198681D01*
X1215933Y-197806D01*
X1212003Y-196056D01*
X1211130Y-194014D01*
X1211567Y-192556D01*
X1212440Y-191681D01*
X1213750Y-191390D01*
X1215060Y-191681D01*
X1216370Y-192556D01*
G01X1248750Y-191390D02*
Y-203056D01*
G01Y-186723D02*
X1248313Y-186431D01*
Y-185848D01*
X1248750Y-185556D01*
X1249187Y-185848D01*
Y-186431D01*
X1248750Y-186723D01*
G01X1262538Y-203056D02*
Y-191390D01*
G01Y-194306D02*
X1263412Y-192848D01*
X1264722Y-191681D01*
X1266468Y-191390D01*
X1267996Y-191681D01*
X1269307Y-192848D01*
X1269962Y-194889D01*
Y-203056D01*
G01X1301250D02*
Y-185556D01*
G01X1322680Y-203056D02*
Y-191390D01*
G01Y-193431D02*
X1321807Y-192265D01*
X1320496Y-191681D01*
X1318968Y-191390D01*
X1317440Y-191973D01*
X1316130Y-193139D01*
X1315256Y-194889D01*
X1314820Y-197223D01*
X1315256Y-199556D01*
X1316130Y-201306D01*
X1317440Y-202473D01*
X1318968Y-203056D01*
X1320496Y-202764D01*
X1321807Y-201890D01*
X1322680Y-200723D01*
G01X1331665Y-208306D02*
X1332975Y-208889D01*
X1334722Y-208306D01*
X1335813Y-207140D01*
X1336687Y-205681D01*
X1337996Y-201015D01*
X1340835Y-191390D01*
G01X1333848D02*
X1337996Y-201015D01*
G01X1350475Y-195181D02*
X1357462D01*
X1356807Y-193139D01*
X1355715Y-191973D01*
X1354187Y-191390D01*
X1352658Y-191681D01*
X1351348Y-192556D01*
X1350475Y-194598D01*
X1350038Y-196348D01*
Y-198098D01*
X1350475Y-199848D01*
X1351567Y-201598D01*
X1352877Y-202764D01*
X1354405Y-203056D01*
X1355933Y-202473D01*
X1357462Y-200723D01*
G01X1368193Y-203056D02*
Y-191390D01*
G01Y-193723D02*
X1369285Y-192556D01*
X1370377Y-191681D01*
X1371905Y-191390D01*
X1372996Y-191681D01*
X1374307Y-192556D01*
G01X1401883Y-185556D02*
Y-203056D01*
X1410617D01*
G01X1418947Y-199556D02*
X1420256Y-201598D01*
X1422003Y-202764D01*
X1423968Y-203056D01*
X1425715Y-202764D01*
X1427462Y-201306D01*
X1428553Y-199556D01*
X1428772Y-197806D01*
X1428335Y-195765D01*
X1426807Y-194306D01*
X1425278Y-193723D01*
X1423313D01*
G01X1425278D02*
X1426588Y-192848D01*
X1427680Y-191390D01*
X1428117Y-189640D01*
X1427680Y-187889D01*
X1426588Y-186431D01*
X1424623Y-185556D01*
X1422658Y-185848D01*
X1420693Y-187015D01*
G01X1441250Y-203639D02*
X1440813Y-203348D01*
Y-202764D01*
X1441250Y-202473D01*
X1441687Y-202764D01*
Y-203348D01*
X1441250Y-203639D01*
G01X2008773Y1616518D02*
X2014013D01*
G01X2011393D02*
Y1599018D01*
G01X2008773D02*
X2014013D01*
G01X2023216D02*
Y1616518D01*
X2028893Y1601935D01*
X2034570Y1616518D01*
Y1599018D01*
G01X2042026D02*
Y1616518D01*
X2047266D01*
X2049013Y1615643D01*
X2050323Y1613601D01*
X2050760Y1611268D01*
X2050323Y1608935D01*
X2049231Y1607185D01*
X2047266Y1606309D01*
X2042026D01*
G01X2062801Y1593185D02*
X2060618Y1596101D01*
X2059526Y1599018D01*
Y1610684D01*
X2060618Y1613601D01*
X2062801Y1616518D01*
G01X2081393Y1599018D02*
X2079646Y1599310D01*
X2078118Y1600476D01*
X2076808Y1602226D01*
X2075934Y1604268D01*
X2075498Y1606601D01*
Y1608935D01*
X2075934Y1611268D01*
X2076808Y1613310D01*
X2078118Y1615059D01*
X2079646Y1616226D01*
X2081393Y1616518D01*
X2083139Y1616226D01*
X2084668Y1615059D01*
X2085978Y1613310D01*
X2086852Y1611268D01*
X2087288Y1608935D01*
Y1606601D01*
X2086852Y1604268D01*
X2085978Y1602226D01*
X2084668Y1600476D01*
X2083139Y1599310D01*
X2081393Y1599018D01*
G01X2095181D02*
Y1616518D01*
G01Y1608060D02*
X2096273Y1609518D01*
X2097365Y1610393D01*
X2099111Y1610684D01*
X2100421Y1610393D01*
X2101950Y1609226D01*
X2102605Y1607476D01*
Y1599018D01*
G01X2109843D02*
Y1610684D01*
G01Y1607476D02*
X2110498Y1608935D01*
X2111590Y1610101D01*
X2113118Y1610684D01*
X2114646Y1610101D01*
X2115738Y1608935D01*
X2116393Y1607476D01*
Y1599018D01*
G01Y1607476D02*
X2117048Y1608935D01*
X2118139Y1610101D01*
X2119668Y1610684D01*
X2121196Y1610101D01*
X2122288Y1608935D01*
X2122943Y1607185D01*
Y1599018D01*
G01X2134985Y1593185D02*
X2137168Y1596101D01*
X2138260Y1599018D01*
Y1610684D01*
X2137168Y1613601D01*
X2134985Y1616518D01*
G01X1987108Y1636001D02*
X1988855Y1634543D01*
X1990820Y1633668D01*
X1992566D01*
X1994313Y1634543D01*
X1995623Y1636001D01*
X1996278Y1638043D01*
X1995841Y1640084D01*
X1994750Y1641835D01*
X1992785Y1643001D01*
X1990165Y1643585D01*
X1988636Y1644751D01*
X1987981Y1646793D01*
X1988418Y1648835D01*
X1989510Y1650293D01*
X1991038Y1651168D01*
X1992566D01*
X1994095Y1650585D01*
X1995405Y1649126D01*
G01X2013560Y1633668D02*
X2004826D01*
Y1651168D01*
X2013560D01*
G01X2010066Y1642710D02*
X2004826D01*
G01X2041573Y1651168D02*
X2046813D01*
G01X2044193D02*
Y1633668D01*
G01X2041573D02*
X2046813D01*
G01X2056016D02*
Y1651168D01*
X2061693Y1636585D01*
X2067370Y1651168D01*
Y1633668D01*
G01X2074826D02*
Y1651168D01*
X2080066D01*
X2081813Y1650293D01*
X2083123Y1648251D01*
X2083560Y1645918D01*
X2083123Y1643585D01*
X2082031Y1641835D01*
X2080066Y1640959D01*
X2074826D01*
G01X2101060Y1633668D02*
X2092326D01*
Y1651168D01*
X2101060D01*
G01X2097566Y1642710D02*
X2092326D01*
G01X2109390Y1633668D02*
Y1651168D01*
X2113756D01*
X2115503Y1650293D01*
X2116813Y1649126D01*
X2117905Y1647377D01*
X2118778Y1645334D01*
X2118996Y1642418D01*
X2118778Y1639501D01*
X2117905Y1637459D01*
X2116813Y1635709D01*
X2115503Y1634543D01*
X2113756Y1633668D01*
X2109390D01*
G01X2126234D02*
X2131693Y1651168D01*
X2137152Y1633668D01*
G01X2135186Y1639793D02*
X2128199D01*
G01X2144171Y1633668D02*
Y1651168D01*
X2154215Y1633668D01*
Y1651168D01*
G01X2171496Y1649709D02*
X2170186Y1650585D01*
X2168658Y1651168D01*
X2166911D01*
X2164946Y1650293D01*
X2163418Y1648835D01*
X2162326Y1647084D01*
X2161453Y1644168D01*
X2161234Y1641543D01*
X2161671Y1638918D01*
X2162326Y1637168D01*
X2163636Y1635418D01*
X2165165Y1634251D01*
X2166693Y1633668D01*
X2168221D01*
X2169750Y1634251D01*
X2171060Y1635126D01*
X2172152Y1636292D01*
G01X2188560Y1633668D02*
X2179826D01*
Y1651168D01*
X2188560D01*
G01X2185066Y1642710D02*
X2179826D01*
G01X2219193Y1651168D02*
Y1633668D01*
G01X2214171Y1651168D02*
X2224215D01*
G01X2231234Y1633668D02*
X2236693Y1651168D01*
X2242152Y1633668D01*
G01X2240186Y1639793D02*
X2233199D01*
G01X2255939Y1643001D02*
X2256813Y1643876D01*
X2257468Y1645334D01*
X2257905Y1647377D01*
X2257468Y1649126D01*
X2256595Y1650293D01*
X2255066Y1651168D01*
X2249171D01*
Y1633668D01*
X2256376D01*
X2257905Y1634834D01*
X2258778Y1636585D01*
X2259215Y1638626D01*
X2258778Y1640668D01*
X2257468Y1642418D01*
X2255939Y1643001D01*
X2249171D01*
G01X2267326Y1651168D02*
Y1633668D01*
X2276060D01*
G01X2293560D02*
X2284826D01*
Y1651168D01*
X2293560D01*
G01X2290066Y1642710D02*
X2284826D01*
G01X2306693Y1633085D02*
X2306256Y1633376D01*
Y1633960D01*
X2306693Y1634251D01*
X2307130Y1633960D01*
Y1633376D01*
X2306693Y1633085D01*
G01Y1640959D02*
X2306256Y1641251D01*
Y1641835D01*
X2306693Y1642126D01*
X2307130Y1641835D01*
Y1641251D01*
X2306693Y1640959D01*
G01X2337326Y1651168D02*
Y1633668D01*
X2346060D01*
G01X2354390Y1637168D02*
X2355699Y1635126D01*
X2357446Y1633960D01*
X2359411Y1633668D01*
X2361158Y1633960D01*
X2362905Y1635418D01*
X2363996Y1637168D01*
X2364215Y1638918D01*
X2363778Y1640959D01*
X2362250Y1642418D01*
X2360721Y1643001D01*
X2358756D01*
G01X2360721D02*
X2362031Y1643876D01*
X2363123Y1645334D01*
X2363560Y1647084D01*
X2363123Y1648835D01*
X2362031Y1650293D01*
X2360066Y1651168D01*
X2358101Y1650876D01*
X2356136Y1649709D01*
G01X2041590Y1566992D02*
X2042899Y1565534D01*
X2044428Y1564660D01*
X2046393Y1564368D01*
X2048358Y1564951D01*
X2049886Y1566118D01*
X2050978Y1568159D01*
X2051196Y1570493D01*
X2050760Y1572826D01*
X2049668Y1574285D01*
X2048139Y1575451D01*
X2046611Y1575743D01*
X2045083Y1575451D01*
X2043118Y1574285D01*
X2043773Y1581868D01*
X2049668D01*
G01X2063893D02*
X2062146Y1581285D01*
X2060836Y1579826D01*
X2059963Y1578077D01*
X2059308Y1575743D01*
X2059090Y1573118D01*
X2059308Y1570493D01*
X2059963Y1568159D01*
X2060836Y1566409D01*
X2062146Y1564951D01*
X2063893Y1564368D01*
X2065639Y1564951D01*
X2066950Y1566409D01*
X2067823Y1568159D01*
X2068478Y1570493D01*
X2068696Y1573118D01*
X2068478Y1575743D01*
X2067823Y1578077D01*
X2066950Y1579826D01*
X2065639Y1581285D01*
X2063893Y1581868D01*
G01X2081393Y1563785D02*
X2080956Y1564076D01*
Y1564660D01*
X2081393Y1564951D01*
X2081830Y1564660D01*
Y1564076D01*
X2081393Y1563785D01*
G01X2098893Y1581868D02*
X2097146Y1581285D01*
X2095836Y1579826D01*
X2094963Y1578077D01*
X2094308Y1575743D01*
X2094090Y1573118D01*
X2094308Y1570493D01*
X2094963Y1568159D01*
X2095836Y1566409D01*
X2097146Y1564951D01*
X2098893Y1564368D01*
X2100639Y1564951D01*
X2101950Y1566409D01*
X2102823Y1568159D01*
X2103478Y1570493D01*
X2103696Y1573118D01*
X2103478Y1575743D01*
X2102823Y1578077D01*
X2101950Y1579826D01*
X2100639Y1581285D01*
X2098893Y1581868D01*
G01X2188593Y1616518D02*
X2191649Y1599018D01*
X2195143Y1616518D01*
X2198636Y1599018D01*
X2201693Y1616518D01*
G01X2210023D02*
X2215263D01*
G01X2212643D02*
Y1599018D01*
G01X2210023D02*
X2215263D01*
G01X2225340D02*
Y1616518D01*
X2229706D01*
X2231453Y1615643D01*
X2232763Y1614476D01*
X2233855Y1612727D01*
X2234728Y1610684D01*
X2234946Y1607768D01*
X2234728Y1604851D01*
X2233855Y1602809D01*
X2232763Y1601059D01*
X2231453Y1599893D01*
X2229706Y1599018D01*
X2225340D01*
G01X2247643Y1616518D02*
Y1599018D01*
G01X2242621Y1616518D02*
X2252665D01*
G01X2260558Y1599018D02*
Y1616518D01*
G01X2269728D02*
Y1599018D01*
G01Y1607768D02*
X2260558D01*
G01X2281551Y1593185D02*
X2279368Y1596101D01*
X2278276Y1599018D01*
Y1610684D01*
X2279368Y1613601D01*
X2281551Y1616518D01*
G01X2293593Y1599018D02*
Y1610684D01*
G01Y1607476D02*
X2294248Y1608935D01*
X2295340Y1610101D01*
X2296868Y1610684D01*
X2298396Y1610101D01*
X2299488Y1608935D01*
X2300143Y1607476D01*
Y1599018D01*
G01Y1607476D02*
X2300798Y1608935D01*
X2301889Y1610101D01*
X2303418Y1610684D01*
X2304946Y1610101D01*
X2306038Y1608935D01*
X2306693Y1607185D01*
Y1599018D01*
G01X2317643Y1610684D02*
Y1599018D01*
G01Y1615351D02*
X2317206Y1615643D01*
Y1616226D01*
X2317643Y1616518D01*
X2318080Y1616226D01*
Y1615643D01*
X2317643Y1615351D01*
G01X2335143Y1599018D02*
Y1616518D01*
G01X2349368Y1601059D02*
X2350460Y1599893D01*
X2351988Y1599018D01*
X2353298D01*
X2354608Y1599601D01*
X2355481Y1600476D01*
X2355918Y1601642D01*
X2355700Y1603393D01*
X2354826Y1604268D01*
X2350896Y1606018D01*
X2350023Y1608060D01*
X2350460Y1609518D01*
X2351333Y1610393D01*
X2352643Y1610684D01*
X2353953Y1610393D01*
X2355263Y1609518D01*
G01X2371235Y1593185D02*
X2373418Y1596101D01*
X2374510Y1599018D01*
Y1610684D01*
X2373418Y1613601D01*
X2371235Y1616518D01*
G01X2251590Y1566992D02*
X2252899Y1565534D01*
X2254428Y1564660D01*
X2256393Y1564368D01*
X2258358Y1564951D01*
X2259886Y1566118D01*
X2260978Y1568159D01*
X2261196Y1570493D01*
X2260760Y1572826D01*
X2259668Y1574285D01*
X2258139Y1575451D01*
X2256611Y1575743D01*
X2255083Y1575451D01*
X2253118Y1574285D01*
X2253773Y1581868D01*
X2259668D01*
G01X2273893Y1563785D02*
X2273456Y1564076D01*
Y1564660D01*
X2273893Y1564951D01*
X2274330Y1564660D01*
Y1564076D01*
X2273893Y1563785D01*
G01X2287245Y1578951D02*
X2288555Y1580701D01*
X2290083Y1581576D01*
X2291830Y1581868D01*
X2294013Y1581285D01*
X2295541Y1579826D01*
X2295978Y1578077D01*
X2295760Y1576326D01*
X2294886Y1574868D01*
X2290520Y1571951D01*
X2288555Y1569910D01*
X2287245Y1566992D01*
X2286808Y1564368D01*
X2295978D01*
G01X2304090Y1566992D02*
X2305399Y1565534D01*
X2306928Y1564660D01*
X2308893Y1564368D01*
X2310858Y1564951D01*
X2312386Y1566118D01*
X2313478Y1568159D01*
X2313696Y1570493D01*
X2313260Y1572826D01*
X2312168Y1574285D01*
X2310639Y1575451D01*
X2309111Y1575743D01*
X2307583Y1575451D01*
X2305618Y1574285D01*
X2306273Y1581868D01*
X2312168D01*
G01X2431393Y1616518D02*
Y1599018D01*
G01X2426371Y1616518D02*
X2436415D01*
G01X2448893Y1599018D02*
Y1606893D01*
X2444526Y1616518D01*
G01X2453260D02*
X2448893Y1606893D01*
G01X2462026Y1599018D02*
Y1616518D01*
X2467266D01*
X2469013Y1615643D01*
X2470323Y1613601D01*
X2470760Y1611268D01*
X2470323Y1608935D01*
X2469231Y1607185D01*
X2467266Y1606309D01*
X2462026D01*
G01X2488260Y1599018D02*
X2479526D01*
Y1616518D01*
X2488260D01*
G01X2484766Y1608060D02*
X2479526D01*
G01X2444308Y1566701D02*
X2446055Y1565243D01*
X2448020Y1564368D01*
X2449766D01*
X2451513Y1565243D01*
X2452823Y1566701D01*
X2453478Y1568743D01*
X2453041Y1570784D01*
X2451950Y1572535D01*
X2449985Y1573701D01*
X2447365Y1574285D01*
X2445836Y1575451D01*
X2445181Y1577493D01*
X2445618Y1579535D01*
X2446710Y1580993D01*
X2448238Y1581868D01*
X2449766D01*
X2451295Y1581285D01*
X2452605Y1579826D01*
G01X2470760Y1564368D02*
X2462026D01*
Y1581868D01*
X2470760D01*
G01X2467266Y1573410D02*
X2462026D01*
G01X2532026Y1599018D02*
Y1616518D01*
X2537485D01*
X2539231Y1615643D01*
X2540323Y1614476D01*
X2540760Y1612143D01*
X2540323Y1609809D01*
X2539013Y1608351D01*
X2537485Y1607476D01*
X2532026D01*
G01X2537485D02*
X2540760Y1599018D01*
G01X2550618Y1606893D02*
X2557605D01*
X2556950Y1608935D01*
X2555858Y1610101D01*
X2554330Y1610684D01*
X2552801Y1610393D01*
X2551491Y1609518D01*
X2550618Y1607476D01*
X2550181Y1605726D01*
Y1603976D01*
X2550618Y1602226D01*
X2551710Y1600476D01*
X2553020Y1599310D01*
X2554548Y1599018D01*
X2556076Y1599601D01*
X2557605Y1601351D01*
G01X2570083Y1599018D02*
Y1613893D01*
X2570520Y1615351D01*
X2571393Y1616226D01*
X2572703Y1616518D01*
X2574013Y1615935D01*
X2574668Y1614476D01*
G01X2572048Y1609518D02*
X2567681D01*
G01X2588893Y1598435D02*
X2588456Y1598726D01*
Y1599310D01*
X2588893Y1599601D01*
X2589330Y1599310D01*
Y1598726D01*
X2588893Y1598435D01*
G01X2619526Y1599018D02*
Y1616518D01*
X2624766D01*
X2626513Y1615643D01*
X2627823Y1613601D01*
X2628260Y1611268D01*
X2627823Y1608935D01*
X2626731Y1607185D01*
X2624766Y1606309D01*
X2619526D01*
G01X2641393Y1599018D02*
Y1616518D01*
G01X2662823Y1599018D02*
Y1610684D01*
G01Y1608643D02*
X2661950Y1609809D01*
X2660639Y1610393D01*
X2659111Y1610684D01*
X2657583Y1610101D01*
X2656273Y1608935D01*
X2655399Y1607185D01*
X2654963Y1604851D01*
X2655399Y1602518D01*
X2656273Y1600768D01*
X2657583Y1599601D01*
X2659111Y1599018D01*
X2660639Y1599310D01*
X2661950Y1600184D01*
X2662823Y1601351D01*
G01X2672681Y1599018D02*
Y1610684D01*
G01Y1607768D02*
X2673555Y1609226D01*
X2674865Y1610393D01*
X2676611Y1610684D01*
X2678139Y1610393D01*
X2679450Y1609226D01*
X2680105Y1607185D01*
Y1599018D01*
G01X2690618Y1606893D02*
X2697605D01*
X2696950Y1608935D01*
X2695858Y1610101D01*
X2694330Y1610684D01*
X2692801Y1610393D01*
X2691491Y1609518D01*
X2690618Y1607476D01*
X2690181Y1605726D01*
Y1603976D01*
X2690618Y1602226D01*
X2691710Y1600476D01*
X2693020Y1599310D01*
X2694548Y1599018D01*
X2696076Y1599601D01*
X2697605Y1601351D01*
G01X2575776Y1581868D02*
Y1564368D01*
X2584510D01*
G01X2593495Y1578951D02*
X2594805Y1580701D01*
X2596333Y1581576D01*
X2598080Y1581868D01*
X2600263Y1581285D01*
X2601791Y1579826D01*
X2602228Y1578077D01*
X2602010Y1576326D01*
X2601136Y1574868D01*
X2596770Y1571951D01*
X2594805Y1569910D01*
X2593495Y1566992D01*
X2593058Y1564368D01*
X2602228D01*
G01X2611213Y1563785D02*
X2619073Y1581868D01*
G01X2628276D02*
Y1564368D01*
X2637010D01*
G01X2652763D02*
Y1581868D01*
X2644684Y1569326D01*
X2655602D01*
G01X2811693Y1576034D02*
Y1564368D01*
G01Y1580701D02*
X2811256Y1580993D01*
Y1581576D01*
X2811693Y1581868D01*
X2812130Y1581576D01*
Y1580993D01*
X2811693Y1580701D01*
G01X2825918Y1566409D02*
X2827010Y1565243D01*
X2828538Y1564368D01*
X2829848D01*
X2831158Y1564951D01*
X2832031Y1565826D01*
X2832468Y1566992D01*
X2832250Y1568743D01*
X2831376Y1569618D01*
X2827446Y1571368D01*
X2826573Y1573410D01*
X2827010Y1574868D01*
X2827883Y1575743D01*
X2829193Y1576034D01*
X2830503Y1575743D01*
X2831813Y1574868D01*
G01X2859171Y1564368D02*
Y1581868D01*
X2869215Y1564368D01*
Y1581868D01*
G01X2881693Y1564368D02*
X2879946Y1564660D01*
X2878418Y1565826D01*
X2877108Y1567576D01*
X2876234Y1569618D01*
X2875798Y1571951D01*
Y1574285D01*
X2876234Y1576618D01*
X2877108Y1578660D01*
X2878418Y1580409D01*
X2879946Y1581576D01*
X2881693Y1581868D01*
X2883439Y1581576D01*
X2884968Y1580409D01*
X2886278Y1578660D01*
X2887152Y1576618D01*
X2887588Y1574285D01*
Y1571951D01*
X2887152Y1569618D01*
X2886278Y1567576D01*
X2884968Y1565826D01*
X2883439Y1564660D01*
X2881693Y1564368D01*
G01X2899193Y1581868D02*
Y1564368D01*
G01X2894171Y1581868D02*
X2904215D01*
G01X2930481Y1576034D02*
Y1567868D01*
X2931355Y1565826D01*
X2932665Y1564660D01*
X2934193Y1564368D01*
X2935721Y1564660D01*
X2937031Y1565826D01*
X2937905Y1567868D01*
G01Y1564368D02*
Y1576034D01*
G01X2948418Y1566409D02*
X2949510Y1565243D01*
X2951038Y1564368D01*
X2952348D01*
X2953658Y1564951D01*
X2954531Y1565826D01*
X2954968Y1566992D01*
X2954750Y1568743D01*
X2953876Y1569618D01*
X2949946Y1571368D01*
X2949073Y1573410D01*
X2949510Y1574868D01*
X2950383Y1575743D01*
X2951693Y1576034D01*
X2953003Y1575743D01*
X2954313Y1574868D01*
G01X2965918Y1572243D02*
X2972905D01*
X2972250Y1574285D01*
X2971158Y1575451D01*
X2969630Y1576034D01*
X2968101Y1575743D01*
X2966791Y1574868D01*
X2965918Y1572826D01*
X2965481Y1571076D01*
Y1569326D01*
X2965918Y1567576D01*
X2967010Y1565826D01*
X2968320Y1564660D01*
X2969848Y1564368D01*
X2971376Y1564951D01*
X2972905Y1566701D01*
G01X2990623Y1581868D02*
Y1564368D01*
G01Y1566992D02*
X2989750Y1565534D01*
X2988439Y1564660D01*
X2986911Y1564368D01*
X2985165Y1564951D01*
X2983855Y1566409D01*
X2982981Y1568159D01*
X2982763Y1570201D01*
X2982981Y1572243D01*
X2983855Y1573993D01*
X2985165Y1575451D01*
X2986911Y1576034D01*
X2988439Y1575743D01*
X2989531Y1575159D01*
X2990623Y1573993D01*
G01X2736890Y1598435D02*
X2746496Y1611268D01*
G01X2741693Y1613601D02*
Y1596101D01*
G01X2746496Y1598435D02*
X2736890Y1611268D01*
G01X2735143Y1604851D02*
X2748243D01*
G01X2773855D02*
X2779531D01*
G01X2806890Y1599018D02*
Y1616518D01*
X2811256D01*
X2813003Y1615643D01*
X2814313Y1614476D01*
X2815405Y1612727D01*
X2816278Y1610684D01*
X2816496Y1607768D01*
X2816278Y1604851D01*
X2815405Y1602809D01*
X2814313Y1601059D01*
X2813003Y1599893D01*
X2811256Y1599018D01*
X2806890D01*
G01X2825918Y1606893D02*
X2832905D01*
X2832250Y1608935D01*
X2831158Y1610101D01*
X2829630Y1610684D01*
X2828101Y1610393D01*
X2826791Y1609518D01*
X2825918Y1607476D01*
X2825481Y1605726D01*
Y1603976D01*
X2825918Y1602226D01*
X2827010Y1600476D01*
X2828320Y1599310D01*
X2829848Y1599018D01*
X2831376Y1599601D01*
X2832905Y1601351D01*
G01X2842981Y1599018D02*
Y1610684D01*
G01Y1607768D02*
X2843855Y1609226D01*
X2845165Y1610393D01*
X2846911Y1610684D01*
X2848439Y1610393D01*
X2849750Y1609226D01*
X2850405Y1607185D01*
Y1599018D01*
G01X2864193D02*
X2862883Y1599310D01*
X2861573Y1600476D01*
X2860699Y1602518D01*
X2860263Y1604851D01*
X2860699Y1607185D01*
X2861573Y1609226D01*
X2862883Y1610393D01*
X2864193Y1610684D01*
X2865503Y1610393D01*
X2866813Y1609226D01*
X2867686Y1607185D01*
X2867905Y1604851D01*
X2867686Y1602518D01*
X2866813Y1600476D01*
X2865503Y1599310D01*
X2864193Y1599018D01*
G01X2881693Y1616518D02*
Y1599018D01*
G01X2878636Y1610684D02*
X2884750D01*
G01X2895918Y1606893D02*
X2902905D01*
X2902250Y1608935D01*
X2901158Y1610101D01*
X2899630Y1610684D01*
X2898101Y1610393D01*
X2896791Y1609518D01*
X2895918Y1607476D01*
X2895481Y1605726D01*
Y1603976D01*
X2895918Y1602226D01*
X2897010Y1600476D01*
X2898320Y1599310D01*
X2899848Y1599018D01*
X2901376Y1599601D01*
X2902905Y1601351D01*
G01X2913418Y1601059D02*
X2914510Y1599893D01*
X2916038Y1599018D01*
X2917348D01*
X2918658Y1599601D01*
X2919531Y1600476D01*
X2919968Y1601642D01*
X2919750Y1603393D01*
X2918876Y1604268D01*
X2914946Y1606018D01*
X2914073Y1608060D01*
X2914510Y1609518D01*
X2915383Y1610393D01*
X2916693Y1610684D01*
X2918003Y1610393D01*
X2919313Y1609518D01*
G01X2951693Y1616518D02*
Y1599018D01*
G01X2948636Y1610684D02*
X2954750D01*
G01X2965481Y1599018D02*
Y1616518D01*
G01Y1608060D02*
X2966573Y1609518D01*
X2967665Y1610393D01*
X2969411Y1610684D01*
X2970721Y1610393D01*
X2972250Y1609226D01*
X2972905Y1607476D01*
Y1599018D01*
G01X2990623D02*
Y1610684D01*
G01Y1608643D02*
X2989750Y1609809D01*
X2988439Y1610393D01*
X2986911Y1610684D01*
X2985383Y1610101D01*
X2984073Y1608935D01*
X2983199Y1607185D01*
X2982763Y1604851D01*
X2983199Y1602518D01*
X2984073Y1600768D01*
X2985383Y1599601D01*
X2986911Y1599018D01*
X2988439Y1599310D01*
X2989750Y1600184D01*
X2990623Y1601351D01*
G01X3004193Y1616518D02*
Y1599018D01*
G01X3001136Y1610684D02*
X3007250D01*
G01X3039193Y1616518D02*
Y1599018D01*
G01X3036136Y1610684D02*
X3042250D01*
G01X3052981Y1599018D02*
Y1616518D01*
G01Y1608060D02*
X3054073Y1609518D01*
X3055165Y1610393D01*
X3056911Y1610684D01*
X3058221Y1610393D01*
X3059750Y1609226D01*
X3060405Y1607476D01*
Y1599018D01*
G01X3074193Y1610684D02*
Y1599018D01*
G01Y1615351D02*
X3073756Y1615643D01*
Y1616226D01*
X3074193Y1616518D01*
X3074630Y1616226D01*
Y1615643D01*
X3074193Y1615351D01*
G01X3088418Y1601059D02*
X3089510Y1599893D01*
X3091038Y1599018D01*
X3092348D01*
X3093658Y1599601D01*
X3094531Y1600476D01*
X3094968Y1601642D01*
X3094750Y1603393D01*
X3093876Y1604268D01*
X3089946Y1606018D01*
X3089073Y1608060D01*
X3089510Y1609518D01*
X3090383Y1610393D01*
X3091693Y1610684D01*
X3093003Y1610393D01*
X3094313Y1609518D01*
G01X3124073Y1616518D02*
X3129313D01*
G01X3126693D02*
Y1599018D01*
G01X3124073D02*
X3129313D01*
G01X3137643D02*
Y1610684D01*
G01Y1607476D02*
X3138298Y1608935D01*
X3139390Y1610101D01*
X3140918Y1610684D01*
X3142446Y1610101D01*
X3143538Y1608935D01*
X3144193Y1607476D01*
Y1599018D01*
G01Y1607476D02*
X3144848Y1608935D01*
X3145939Y1610101D01*
X3147468Y1610684D01*
X3148996Y1610101D01*
X3150088Y1608935D01*
X3150743Y1607185D01*
Y1599018D01*
G01X3157763Y1593185D02*
Y1610684D01*
G01Y1608060D02*
X3158855Y1609518D01*
X3159946Y1610393D01*
X3161693Y1610684D01*
X3163221Y1610393D01*
X3164750Y1608935D01*
X3165405Y1606893D01*
X3165623Y1604851D01*
X3165405Y1602809D01*
X3164750Y1600768D01*
X3163439Y1599601D01*
X3161693Y1599018D01*
X3160165Y1599310D01*
X3158636Y1600184D01*
X3157763Y1601351D01*
G01X3175918Y1606893D02*
X3182905D01*
X3182250Y1608935D01*
X3181158Y1610101D01*
X3179630Y1610684D01*
X3178101Y1610393D01*
X3176791Y1609518D01*
X3175918Y1607476D01*
X3175481Y1605726D01*
Y1603976D01*
X3175918Y1602226D01*
X3177010Y1600476D01*
X3178320Y1599310D01*
X3179848Y1599018D01*
X3181376Y1599601D01*
X3182905Y1601351D01*
G01X3200623Y1616518D02*
Y1599018D01*
G01Y1601642D02*
X3199750Y1600184D01*
X3198439Y1599310D01*
X3196911Y1599018D01*
X3195165Y1599601D01*
X3193855Y1601059D01*
X3192981Y1602809D01*
X3192763Y1604851D01*
X3192981Y1606893D01*
X3193855Y1608643D01*
X3195165Y1610101D01*
X3196911Y1610684D01*
X3198439Y1610393D01*
X3199531Y1609809D01*
X3200623Y1608643D01*
G01X3218123Y1599018D02*
Y1610684D01*
G01Y1608643D02*
X3217250Y1609809D01*
X3215939Y1610393D01*
X3214411Y1610684D01*
X3212883Y1610101D01*
X3211573Y1608935D01*
X3210699Y1607185D01*
X3210263Y1604851D01*
X3210699Y1602518D01*
X3211573Y1600768D01*
X3212883Y1599601D01*
X3214411Y1599018D01*
X3215939Y1599310D01*
X3217250Y1600184D01*
X3218123Y1601351D01*
G01X3227981Y1599018D02*
Y1610684D01*
G01Y1607768D02*
X3228855Y1609226D01*
X3230165Y1610393D01*
X3231911Y1610684D01*
X3233439Y1610393D01*
X3234750Y1609226D01*
X3235405Y1607185D01*
Y1599018D01*
G01X3252686Y1609226D02*
X3251158Y1610393D01*
X3249848Y1610684D01*
X3248101Y1610101D01*
X3246791Y1608935D01*
X3245918Y1606893D01*
X3245699Y1604851D01*
X3245918Y1602809D01*
X3246791Y1601059D01*
X3248101Y1599601D01*
X3249848Y1599018D01*
X3251376Y1599601D01*
X3252686Y1600768D01*
G01X3263418Y1606893D02*
X3270405D01*
X3269750Y1608935D01*
X3268658Y1610101D01*
X3267130Y1610684D01*
X3265601Y1610393D01*
X3264291Y1609518D01*
X3263418Y1607476D01*
X3262981Y1605726D01*
Y1603976D01*
X3263418Y1602226D01*
X3264510Y1600476D01*
X3265820Y1599310D01*
X3267348Y1599018D01*
X3268876Y1599601D01*
X3270405Y1601351D01*
G01X0Y-137756D02*
G03X15000Y-152756I15000J0D01*
G01X0Y-137756D02*
G03X15000Y-152756I15000J0D01*
G01X0Y-11811D02*
Y-137756D01*
G01Y-11811D02*
Y-137756D01*
G01X854331Y-152756D02*
X15000D01*
G01X854331D02*
X15000D01*
G01X23622Y-7874D02*
G03Y0I0J3937D01*
G01Y-7874D02*
G03Y0I0J3937D01*
G01X0Y3937D02*
G03X3937Y0I3937J0D01*
G01Y-7874D02*
X23622D01*
G01X0Y3937D02*
G03X3937Y0I3937J0D01*
G01Y-7874D02*
X23622D01*
G01X3937D02*
G03X0Y-11811I0J-3937D01*
G01X3937Y-7874D02*
G03X0Y-11811I0J-3937D01*
G01X3937Y0D02*
X397638D01*
G01X3937D02*
X397638D01*
G01X0Y1370866D02*
Y3937D01*
G01Y1370866D02*
Y3937D01*
G01X3937Y1374803D02*
G03X0Y1370866I0J-3937D01*
G01X3937Y1374803D02*
G03X0Y1370866I0J-3937D01*
G01X23622Y1374803D02*
G03Y1382677I0J3937D01*
G01Y1374803D02*
G03Y1382677I0J3937D01*
G01X3937D02*
X23622D01*
G01X0Y1386614D02*
G03X3937Y1382677I3937J0D01*
G01D02*
X23622D01*
G01X0Y1386614D02*
G03X3937Y1382677I3937J0D01*
G01Y1374803D02*
X746850D01*
G01D02*
X3937D01*
G01X0Y1386614D02*
Y1643268D01*
G01Y1386614D02*
Y1643268D01*
G01X15000Y1658268D02*
G03X0Y1643268I0J-15000D01*
G01X15000Y1658268D02*
G03X0Y1643268I0J-15000D01*
G01X775591Y1658268D02*
X15000D01*
G01X775591D02*
X15000D01*
G01X54331Y-7874D02*
X323228D01*
G01X54331D02*
X323228D01*
G01X54331Y0D02*
G03Y-7874I0J-3937D01*
G01Y0D02*
G03Y-7874I0J-3937D01*
G01Y1382677D02*
G03Y1374803I0J-3937D01*
G01Y1382677D02*
G03Y1374803I0J-3937D01*
G01Y1382677D02*
X353740D01*
G01X54331D02*
X353740D01*
G01X114295Y378885D02*
G03X148106I16905J-13531D01*
G01X114295D02*
G03X148106I16905J-13531D01*
G01X114295D02*
G03X121220Y392016I-30737J24602D01*
G01X114295Y378885D02*
G03X121220Y392016I-30737J24602D01*
G01X114295Y831641D02*
G03X121220Y844772I-30737J24601D01*
G01X114295Y831641D02*
G03X121220Y844772I-30737J24602D01*
G01X114295Y831641D02*
G03X148106I16905J-13531D01*
G01X114295D02*
G03X148106I16905J-13531D01*
G01X114295Y1284397D02*
G03X148106I16905J-13531D01*
G01X114295D02*
G03X148106I16905J-13531D01*
G01X114295D02*
G03X121220Y1297528I-30737J24601D01*
G01X114295Y1284397D02*
G03X121220Y1297528I-30737J24602D01*
G01X141181Y392016D02*
G03X121220I-9980J-3039D01*
G01X141181D02*
G03X148106Y378885I37662J11471D01*
G01X141181Y392016D02*
G03X121220I-9980J-3039D01*
G01X141181D02*
G03X148106Y378885I37662J11471D01*
G01X141181Y844772D02*
G03X148106Y831641I37662J11471D01*
G01X141181Y844772D02*
G03X148106Y831641I37662J11471D01*
G01X141181Y844772D02*
G03X121220I-9980J-3040D01*
G01X141181D02*
G03X121220I-9980J-3039D01*
G01X141181Y1297528D02*
G03X121220I-9980J-3040D01*
G01X141181D02*
G03X148106Y1284397I37662J11471D01*
G01X141181Y1297528D02*
G03X121220I-9980J-3040D01*
G01X141181D02*
G03X148106Y1284397I37662J11471D01*
G01X323228Y-7874D02*
G03Y0I0J3937D01*
G01Y-7874D02*
G03Y0I0J3937D01*
G01X362598D02*
G03Y-7874I0J-3937D01*
G01Y0D02*
G03Y-7874I0J-3937D01*
G01X362327Y378885D02*
G03X396138I16905J-13531D01*
G01X362327D02*
G03X396138I16905J-13531D01*
G01X362327D02*
G03X369252Y392016I-30737J24602D01*
G01X362327Y378885D02*
G03X369252Y392016I-30737J24602D01*
G01X362327Y831641D02*
G03X369252Y844772I-30737J24602D01*
G01X362327Y831641D02*
G03X369252Y844772I-30737J24602D01*
G01X362327Y831641D02*
G03X396138I16905J-13531D01*
G01X362327D02*
G03X396138I16905J-13531D01*
G01X362327Y1284397D02*
G03X396138I16905J-13531D01*
G01X362327D02*
G03X396138I16905J-13531D01*
G01X362327D02*
G03X369252Y1297528I-30737J24602D01*
G01X362327Y1284397D02*
G03X369252Y1297528I-30737J24602D01*
G01X353740Y1374803D02*
G03Y1382677I0J3937D01*
G01Y1374803D02*
G03Y1382677I0J3937D01*
G01X401575Y3937D02*
Y55118D01*
G01X397638Y0D02*
G03X401575Y3937I0J3937D01*
G01X409449D02*
Y51181D01*
G01X397638Y-7874D02*
G03X409449Y3937I0J11811D01*
G01X397638Y0D02*
G03X401575Y3937I0J3937D01*
G01D02*
Y55118D01*
G01X409449Y3937D02*
Y51181D01*
G01X397638Y-7874D02*
G03X409449Y3937I0J11811D01*
G01X362598Y-7874D02*
X397638D01*
G01X362598D02*
X397638D01*
G01X405512Y59055D02*
G03X401575Y55118I0J-3937D01*
G01X405512Y59055D02*
G03X401575Y55118I0J-3937D01*
G01X405512Y59055D02*
X586614D01*
G01X409449Y51181D02*
X582677D01*
G01X405512Y59055D02*
X586614D01*
G01X409449Y51181D02*
X582677D01*
G01X389213Y392016D02*
G03X396138Y378885I37662J11471D01*
G01X389213Y392016D02*
G03X396138Y378885I37662J11471D01*
G01X389213Y392016D02*
G03X369252I-9981J-3039D01*
G01X389213D02*
G03X369252I-9981J-3039D01*
G01X389213Y844772D02*
G03X396138Y831641I37662J11471D01*
G01X389213Y844772D02*
G03X396138Y831641I37662J11471D01*
G01X389213Y844772D02*
G03X369252I-9981J-3040D01*
G01X389213D02*
G03X369252I-9981J-3039D01*
G01X389213Y1297528D02*
G03X396138Y1284397I37662J11471D01*
G01X389213Y1297528D02*
G03X396138Y1284397I37662J11471D01*
G01X389213Y1297528D02*
G03X369252I-9981J-3040D01*
G01X389213D02*
G03X369252I-9981J-3040D01*
G01X393110Y1382677D02*
G03Y1374803I0J-3937D01*
G01Y1382677D02*
X692520D01*
G01X393110D02*
X692520D01*
G01X393110D02*
G03Y1374803I0J-3937D01*
G01X523327Y829921D02*
G03X483169I-20079J0D01*
G01X523327D02*
G03I-20079J0D01*
G01X483169D02*
G03X523327I20079J0D01*
G01X594488Y-7874D02*
X628765D01*
G01X594488D02*
X628765D01*
G01X590551Y55118D02*
Y3937D01*
G01D02*
G03X594488Y0I3937J0D01*
G01X582677Y51181D02*
Y3937D01*
G01D02*
G03X594488Y-7874I11811J0D01*
G01X590551Y55118D02*
Y3937D01*
G01D02*
G03X594488Y0I3937J0D01*
G01X582677Y51181D02*
Y3937D01*
G01D02*
G03X594488Y-7874I11811J0D01*
G01Y0D02*
X783465D01*
G01X594488D02*
X783465D01*
G01X590551Y55118D02*
G03X586614Y59055I-3937J0D01*
G01X590551Y55118D02*
G03X586614Y59055I-3937J0D01*
G01X628765Y-7874D02*
G03Y0I0J3937D01*
G01Y-7874D02*
G03Y0I0J3937D01*
G01X610358Y378885D02*
G03X644169I16906J-13531D01*
G01X610358D02*
G03X644169I16906J-13531D01*
G01X637244Y392016D02*
G03X644169Y378885I37662J11471D01*
G01X637244Y392016D02*
G03X644169Y378885I37662J11471D01*
G01X637244Y392016D02*
G03X617283I-9980J-3039D01*
G01X637244D02*
G03X617283I-9980J-3039D01*
G01X610358Y378885D02*
G03X617283Y392016I-30737J24602D01*
G01X610358Y378885D02*
G03X617283Y392016I-30737J24602D01*
G01X637244Y844772D02*
G03X644169Y831641I37662J11471D01*
G01X637244Y844772D02*
G03X644169Y831641I37662J11471D01*
G01X610358D02*
G03X617283Y844772I-30737J24601D01*
G01X610358Y831641D02*
G03X617283Y844772I-30737J24602D01*
G01X610358Y831641D02*
G03X644169I16906J-13531D01*
G01X610358D02*
G03X644169I16906J-13531D01*
G01X637244Y844772D02*
G03X617283I-9980J-3040D01*
G01X637244D02*
G03X617283I-9980J-3039D01*
G01X610358Y1284397D02*
G03X644169I16906J-13531D01*
G01X610358D02*
G03X644169I16906J-13531D01*
G01X637244Y1297528D02*
G03X644169Y1284397I37662J11471D01*
G01X637244Y1297528D02*
G03X644169Y1284397I37662J11471D01*
G01X610358D02*
G03X617283Y1297528I-30737J24601D01*
G01X637244D02*
G03X617283I-9980J-3040D01*
G01X610358Y1284397D02*
G03X617283Y1297528I-30737J24602D01*
G01X637244D02*
G03X617283I-9980J-3040D01*
G01X659474Y0D02*
G03Y-7874I0J-3937D01*
G01Y0D02*
G03Y-7874I0J-3937D01*
G01D02*
X780203D01*
G01X659474D02*
X780203D01*
G01X692520Y1374803D02*
G03Y1382677I0J3937D01*
G01Y1374803D02*
G03Y1382677I0J3937D01*
G01X746850Y1374803D02*
G03X750787Y1378740I0J3937D01*
G01X746850Y1374803D02*
G03X750787Y1378740I0J3937D01*
G01X723228Y1382677D02*
G03Y1374803I0J-3937D01*
G01Y1382677D02*
X742913D01*
G01X723228D02*
X742913D01*
G01X723228D02*
G03Y1374803I0J-3937D01*
G01X742913Y1464567D02*
Y1382677D01*
G01Y1464567D02*
Y1382677D01*
G01X754724Y1476378D02*
G03X742913Y1464567I0J-11811D01*
G01X754724Y1476378D02*
G03X742913Y1464567I0J-11811D01*
G01X862205Y-7874D02*
X791339D01*
G01X787402Y-3937D02*
G03X791339Y-7874I3937J0D01*
G01X787402Y-3937D02*
G03X791339Y-7874I3937J0D01*
G01D02*
X862205D01*
G01X858268Y-15748D02*
X791339D01*
G01X858268D02*
X791339D01*
G01X787402Y-3937D02*
G03X783465Y0I-3937J0D01*
G01X787402Y-3937D02*
G03X783465Y0I-3937J0D01*
G01X780203Y-7874D02*
G03X791339Y-15748I11136J3937D01*
G01X780203Y-7874D02*
G03X791339Y-15748I11136J3937D01*
G01X779551Y264712D02*
G03X813362I16905J-13531D01*
G01X779551D02*
G03X813362I16905J-13531D01*
G01X779551D02*
G03X786476Y277843I-30737J24601D01*
G01X806437D02*
G03X786476I-9981J-3040D01*
G01X779551Y264712D02*
G03X786476Y277843I-30737J24602D01*
G01X806437D02*
G03X786476I-9981J-3040D01*
G01X779551Y737153D02*
G03X786476Y750284I-30737J24601D01*
G01X779551Y737154D02*
G03X786476Y750284I-30736J24602D01*
G01X779551Y737153D02*
G03X813362I16905J-13531D01*
G01X779551D02*
G03X813362I16905J-13531D01*
G01X806437Y750284D02*
G03X786476I-9981J-3040D01*
G01X806437D02*
G03X786476I-9981J-3040D01*
G01X750787Y1464567D02*
Y1378740D01*
G01Y1464567D02*
Y1378740D01*
G01X783465Y1468504D02*
G03X787402Y1472441I0J3937D01*
G01X783465Y1468504D02*
G03X787402Y1472441I0J3937D01*
G01X783465Y1468504D02*
X754724D01*
G01D02*
G03X750787Y1464567I0J-3937D01*
G01X783465Y1468504D02*
X754724D01*
G01D02*
G03X750787Y1464567I0J-3937D01*
G01X779528Y1476378D02*
X754724D01*
G01X779528D02*
X754724D01*
G01X787402Y1654331D02*
Y1472441D01*
G01X779528Y1596063D02*
Y1476378D01*
G01X787402Y1654331D02*
Y1472441D01*
G01X779528Y1596063D02*
Y1476378D01*
G01X787402Y1596063D02*
G03X779528I-3937J0D01*
G01X787402D02*
G03X779528I-3937J0D01*
G01X1216535Y1658268D02*
X791339D01*
G01D02*
G03X787402Y1654331I0J-3937D01*
G01X779528D02*
G03X775591Y1658268I-3937J0D01*
G01X1216535D02*
X791339D01*
G01D02*
G03X787402Y1654331I0J-3937D01*
G01X779528D02*
G03X775591Y1658268I-3937J0D01*
G01X779528Y1654331D02*
Y1626772D01*
G01D02*
G03X787402I3937J0D01*
G01X779528Y1654331D02*
Y1626772D01*
G01D02*
G03X787402I3937J0D01*
G01X806437Y277843D02*
G03X813362Y264712I37662J11471D01*
G01X806437Y277843D02*
G03X813362Y264712I37662J11471D01*
G01X806437Y750284D02*
G03X813362Y737153I37662J11471D01*
G01X806437Y750284D02*
G03X813362Y737154I37661J11472D01*
G01X866142Y-148819D02*
Y-11811D01*
G01Y-148819D02*
G03X870079Y-152756I3937J0D01*
G01X866142Y-11811D02*
Y-148819D01*
G01D02*
G03X870079Y-152756I3937J0D01*
G01X866142Y-129134D02*
G03X858268I-3937J0D01*
G01X866142D02*
G03X858268I-3937J0D01*
G01Y-148819D02*
Y-129134D01*
G01X854331Y-152756D02*
G03X858268Y-148819I0J3937D01*
G01D02*
Y-129134D01*
G01X854331Y-152756D02*
G03X858268Y-148819I0J3937D01*
G01X1177165Y-152756D02*
X870079D01*
G01D02*
X1177165D01*
G01X858268Y-98425D02*
Y-15748D01*
G01Y-98425D02*
Y-15748D01*
G01Y-98425D02*
G03X866142I3937J0D01*
G01X858268D02*
G03X866142I3937J0D01*
G01Y-11811D02*
G03X862205Y-7874I-3937J0D01*
G01X866142Y-11811D02*
G03X862205Y-7874I-3937J0D01*
G01X927032Y-57820D02*
G03X962731I17850J-12259D01*
G01X927032Y-57821D02*
G03X962732I17850J-12258D01*
G01X927032Y-57820D02*
G03X935199Y-42571I-64908J44575D01*
G01X954565D02*
G03X935199I-9683J-3885D01*
G01X927032Y-57821D02*
G03X935199Y-42571I-64909J44573D01*
G01X954564D02*
G03X935199I-9682J-3885D01*
G01X944512Y1089122D02*
G03X978323I16905J-13531D01*
G01X944512Y1089121D02*
G03X978323I16905J-13531D01*
G01X944512Y1431641D02*
G03X978323I16905J-13531D01*
G01X944512D02*
G03X978323I16905J-13531D01*
G01X954565Y-42571D02*
G03X962731Y-57820I73077J29322D01*
G01X954564Y-42570D02*
G03X962732Y-57821I73076J29324D01*
G01X971398Y1102252D02*
G03X978323Y1089122I37661J11472D01*
G01X971398Y1102252D02*
G03X978323Y1089121I37662J11471D01*
G01X971398Y1102252D02*
G03X951437I-9980J-3039D01*
G01X971398D02*
G03X951437I-9980J-3039D01*
G01X944512Y1089122D02*
G03X951437Y1102252I-30737J24602D01*
G01X944512Y1089121D02*
G03X951437Y1102252I-30737J24602D01*
G01X971398Y1444772D02*
G03X978323Y1431641I37662J11471D01*
G01X971398Y1444772D02*
G03X978323Y1431641I37662J11471D01*
G01X971398Y1444772D02*
G03X951437I-9980J-3040D01*
G01X944512Y1431641D02*
G03X951437Y1444772I-30737J24602D01*
G01X944512Y1431641D02*
G03X951437Y1444772I-30737J24602D01*
G01X971398D02*
G03X951437I-9980J-3039D01*
G01X1181102Y-148819D02*
Y-3937D01*
G01X1177165Y-152756D02*
G03X1181102Y-148819I0J3937D01*
G01X1177165Y-152756D02*
G03X1181102Y-148819I0J3937D01*
G01D02*
Y-3937D01*
G01Y-94488D02*
G03X1188976I3937J0D01*
G01X1181102D02*
G03X1188976I3937J0D01*
G01Y-125197D02*
G03X1181102I-3937J0D01*
G01X1188976D02*
G03X1181102I-3937J0D01*
G01X1185039Y0D02*
G03X1181102Y-3937I0J-3937D01*
G01X1185039Y0D02*
G03X1181102Y-3937I0J-3937D01*
G01X1164984Y557626D02*
G03X1198795I16906J-13531D01*
G01X1164984Y557625D02*
G03X1198795I16906J-13531D01*
G01X1191870Y570756D02*
G03X1171909I-9980J-3039D01*
G01X1191870D02*
G03X1171909I-9980J-3039D01*
G01X1164984Y557626D02*
G03X1171909Y570756I-30736J24602D01*
G01X1164984Y557625D02*
G03X1171909Y570756I-30737J24602D01*
G01X1164984Y971011D02*
G03X1198795I16906J-13531D01*
G01X1164984D02*
G03X1198795I16906J-13531D01*
G01X1191870Y984142D02*
G03X1171909I-9980J-3040D01*
G01X1191870D02*
G03X1171909I-9980J-3039D01*
G01X1164984Y971011D02*
G03X1171909Y984142I-30737J24602D01*
G01X1164984Y971011D02*
G03X1171909Y984142I-30737J24602D01*
G01X1164173Y1378740D02*
Y1468504D01*
G01X1930906Y1374803D02*
X1168110D01*
G01X1164173Y1378740D02*
G03X1168110Y1374803I3937J0D01*
G01X1172047Y1382677D02*
Y1464567D01*
G01X1195669Y1382677D02*
X1172047D01*
G01X1930906Y1374803D02*
X1168110D01*
G01X1164173Y1378740D02*
G03X1168110Y1374804I3937J1D01*
G01X1164173Y1378740D02*
Y1468504D01*
G01X1172047Y1382677D02*
Y1464567D01*
G01X1195669Y1382677D02*
X1172047D01*
G01X1168110Y1472441D02*
G03X1164173Y1468504I0J-3937D01*
G01X1168110Y1472441D02*
G03X1164173Y1468504I0J-3937D01*
G01X1172047Y1464567D02*
X1216535D01*
G01X1172047D02*
X1216535D01*
G01X1168110Y1472441D02*
X1216535D01*
G01X1168110D02*
X1216535D01*
G01X1164984Y1561563D02*
G03X1171909Y1574693I-30736J24602D01*
G01X1164984Y1561562D02*
G03X1171909Y1574693I-30737J24602D01*
G01X1164984Y1561563D02*
G03X1198795I16906J-13531D01*
G01X1164984Y1561562D02*
G03X1198795I16906J-13531D01*
G01X1191870Y1574693D02*
G03X1171909I-9980J-3039D01*
G01X1191870D02*
G03X1171909I-9980J-3039D01*
G01X1188976Y-148819D02*
Y-125197D01*
G01Y-148819D02*
G03X1192913Y-152756I3937J0D01*
G01X1188976Y-148819D02*
Y-125197D01*
G01Y-148819D02*
G03X1192913Y-152756I3937J0D01*
G01D02*
X1919843D01*
G01X1192913D02*
X1919843D01*
G01X1188976Y-94488D02*
Y-7874D01*
G01Y-94488D02*
Y-7874D01*
G01X1185039Y0D02*
X1366142D01*
G01X1188976Y-7874D02*
X1315748D01*
G01X1185039Y0D02*
X1366142D01*
G01X1188976Y-7874D02*
X1315748D01*
G01X1191870Y570756D02*
G03X1198795Y557626I37662J11472D01*
G01X1191870Y570756D02*
G03X1198795Y557626I37662J11472D01*
G01X1191870Y984142D02*
G03X1198795Y971011I37662J11471D01*
G01X1191870Y984142D02*
G03X1198795Y971011I37662J11471D01*
G01X1524606Y1382677D02*
X1226378D01*
G01X1524606D02*
X1226378D01*
G01X1195669Y1374803D02*
G03Y1382677I0J3937D01*
G01X1226378D02*
G03Y1374803I0J-3937D01*
G01X1195669D02*
G03Y1382677I0J3937D01*
G01X1226378D02*
G03Y1374803I0J-3937D01*
G01X1216535Y1464567D02*
G03X1228346Y1476378I0J11811D01*
G01X1216535Y1464567D02*
G03X1228346Y1476378I0J11811D01*
G01Y1592126D02*
Y1476378D01*
G01Y1592126D02*
Y1476378D01*
G01X1220472Y1654331D02*
Y1476378D01*
G01X1216535Y1472441D02*
G03X1220472Y1476378I0J3937D01*
G01X1216535Y1472441D02*
G03X1220472Y1476378I0J3937D01*
G01D02*
Y1654331D01*
G01X1191870Y1574693D02*
G03X1198795Y1561563I37662J11472D01*
G01X1191870Y1574693D02*
G03X1198795Y1561562I37662J11471D01*
G01X1228346Y1592126D02*
G03X1220472I-3937J0D01*
G01X1228346D02*
G03X1220472I-3937J0D01*
G01X1232283Y1658268D02*
X1442382D01*
G01X1232283D02*
G03X1228346Y1654331I0J-3937D01*
G01X1232283Y1658268D02*
X1442382D01*
G01X1232283D02*
G03X1228346Y1654331I0J-3937D01*
G01D02*
Y1622835D01*
G01Y1654331D02*
Y1622835D01*
G01X1220472Y1654331D02*
G03X1216535Y1658268I-3937J0D01*
G01X1220472Y1654331D02*
G03X1216535Y1658268I-3937J0D01*
G01X1220472Y1622835D02*
G03X1228346I3937J0D01*
G01X1220472D02*
G03X1228346I3937J0D01*
G01X1284965Y378885D02*
G03X1318776I16906J-13531D01*
G01X1284965D02*
G03X1318775I16905J-13531D01*
G01X1284965Y831641D02*
G03X1318776I16906J-13531D01*
G01X1284965D02*
G03X1318775I16905J-13531D01*
G01X1284965Y1284397D02*
G03X1318776I16906J-13531D01*
G01X1284965D02*
G03X1318775I16905J-13531D01*
G01X1315748Y-7874D02*
G03Y0I0J3937D01*
G01Y-7874D02*
G03Y0I0J3937D01*
G01X1311850Y392016D02*
G03X1291890I-9980J-3040D01*
G01X1311850D02*
G03X1318776Y378885I37662J11473D01*
G01X1311851Y392016D02*
G03X1291890I-9980J-3039D01*
G01X1311851D02*
G03X1318775Y378885I37663J11469D01*
G01X1284965D02*
G03X1291890Y392016I-30737J24602D01*
G01X1284965Y378885D02*
G03X1291890Y392016I-30737J24602D01*
G01X1284965Y831641D02*
G03X1291890Y844772I-30737J24602D01*
G01X1311850D02*
G03X1318776Y831641I37662J11473D01*
G01X1284965D02*
G03X1291890Y844772I-30737J24602D01*
G01X1311851D02*
G03X1318775Y831641I37663J11469D01*
G01X1311850Y844772D02*
G03X1291890I-9980J-3040D01*
G01X1311851D02*
G03X1291890I-9980J-3039D01*
G01X1284965Y1284397D02*
G03X1291890Y1297528I-30737J24602D01*
G01X1311850D02*
G03X1291890I-9980J-3040D01*
G01X1311850D02*
G03X1318776Y1284397I37661J11473D01*
G01X1284965D02*
G03X1291890Y1297528I-30737J24602D01*
G01X1311851D02*
G03X1291890I-9980J-3040D01*
G01X1311851D02*
G03X1318775Y1284397I37663J11469D01*
G01X1377953Y3937D02*
Y51181D01*
G01Y3937D02*
Y51181D01*
G01X1370079Y3937D02*
Y55118D01*
G01X1366142Y0D02*
G03X1370079Y3937I0J3937D01*
G01X1366142Y-7874D02*
G03X1377953Y3937I0J11811D01*
G01X1346457Y-7874D02*
X1366142D01*
G01Y0D02*
G03X1370079Y3937I0J3937D01*
G01D02*
Y55118D01*
G01X1346457Y-7874D02*
X1366142D01*
G01D02*
G03X1377953Y3937I0J11811D01*
G01X1346457Y0D02*
G03Y-7874I0J-3937D01*
G01Y0D02*
G03Y-7874I0J-3937D01*
G01X1374016Y59055D02*
G03X1370079Y55118I0J-3937D01*
G01X1374016Y59056D02*
G03X1370079Y55118I0J-3937D01*
G01X1374016Y59055D02*
X1555118D01*
G01X1377953Y51181D02*
X1551181D01*
G01X1374016Y59055D02*
X1555118D01*
G01X1377953Y51181D02*
X1551181D01*
G01X1442382Y1658268D02*
G03X1450256I3937J0D01*
G01X1442382D02*
G03X1450256I3937J0D01*
G01D02*
X1919843D01*
G01X1450256D02*
X1919843D01*
G01X1562992Y0D02*
X1930906D01*
G01X1559055Y55118D02*
Y3937D01*
G01D02*
G03X1562992Y0I3937J0D01*
G01Y-7874D02*
X1593701D01*
G01X1559055Y55118D02*
Y3937D01*
G01D02*
G03X1562992Y0I3937J0D01*
G01D02*
X1930906D01*
G01X1562992Y-7874D02*
X1593701D01*
G01X1551181Y51181D02*
Y3937D01*
G01D02*
G03X1562992Y-7874I11811J0D01*
G01X1551181Y51181D02*
Y3937D01*
G01D02*
G03X1562992Y-7874I11811J0D01*
G01X1559055Y55118D02*
G03X1555118Y59055I-3937J0D01*
G01X1559055Y55118D02*
G03X1555118Y59055I-3937J0D01*
G01X1532996Y378885D02*
G03X1566807I16906J-13531D01*
G01X1532996D02*
G03X1566807I16906J-13531D01*
G01X1559882Y392016D02*
G03X1566807Y378885I37662J11471D01*
G01X1559882Y392016D02*
G03X1566807Y378885I37662J11471D01*
G01X1559882Y392016D02*
G03X1539921I-9980J-3039D01*
G01X1559882D02*
G03X1539921I-9980J-3039D01*
G01X1532996Y378885D02*
G03X1539921Y392016I-30737J24602D01*
G01X1532996Y378885D02*
G03X1539921Y392016I-30737J24602D01*
G01X1559882Y844772D02*
G03X1566807Y831641I37662J11471D01*
G01X1559882Y844772D02*
G03X1566807Y831641I37662J11471D01*
G01X1532996D02*
G03X1539921Y844772I-30737J24602D01*
G01X1532996Y831641D02*
G03X1539921Y844772I-30737J24602D01*
G01X1532996Y831641D02*
G03X1566807I16906J-13531D01*
G01X1532996D02*
G03X1566807I16906J-13531D01*
G01X1559882Y844772D02*
G03X1539921I-9980J-3040D01*
G01X1559882D02*
G03X1539921I-9980J-3039D01*
G01X1532996Y1284397D02*
G03X1566807I16906J-13531D01*
G01X1532996D02*
G03X1566807I16906J-13531D01*
G01X1559882Y1297528D02*
G03X1566807Y1284397I37662J11471D01*
G01X1559882Y1297528D02*
G03X1566807Y1284397I37662J11471D01*
G01X1559882Y1297528D02*
G03X1539921I-9980J-3040D01*
G01X1532996Y1284397D02*
G03X1539921Y1297528I-30737J24602D01*
G01X1532996Y1284397D02*
G03X1539921Y1297528I-30737J24602D01*
G01X1559882D02*
G03X1539921I-9980J-3040D01*
G01X1563976Y1382677D02*
G03Y1374803I0J-3937D01*
G01Y1382677D02*
G03Y1374803I0J-3937D01*
G01X1524606D02*
G03Y1382677I0J3937D01*
G01Y1374803D02*
G03Y1382677I0J3937D01*
G01X1864567D02*
X1563976D01*
G01X1864567D02*
X1563976D01*
G01X1593701Y-7874D02*
G03Y0I0J3937D01*
G01Y-7874D02*
G03Y0I0J3937D01*
G01X1633071D02*
G03Y-7874I0J-3937D01*
G01D02*
X1880512D01*
G01X1633071D02*
X1880512D01*
G01X1633071Y0D02*
G03Y-7874I0J-3937D01*
G01X1693996Y829921D02*
G03X1653839I-20078J0D01*
G01X1693996D02*
G03I-20079J0D01*
G01X1653839D02*
G03X1693996I20078J0D01*
G01X1781028Y378885D02*
G03X1814839I16906J-13531D01*
G01X1781028D02*
G03X1814838I16905J-13531D01*
G01X1807913Y392016D02*
G03X1814839Y378885I37662J11473D01*
G01X1807914Y392016D02*
G03X1814838Y378885I37663J11469D01*
G01X1807913Y392016D02*
G03X1787953I-9980J-3040D01*
G01X1807914D02*
G03X1787953I-9980J-3039D01*
G01X1781028Y378885D02*
G03X1787953Y392016I-30737J24602D01*
G01X1781028Y378885D02*
G03X1787953Y392016I-30737J24602D01*
G01X1807913Y844772D02*
G03X1814839Y831641I37662J11473D01*
G01X1807914Y844772D02*
G03X1814838Y831641I37663J11469D01*
G01X1781028D02*
G03X1787953Y844772I-30737J24602D01*
G01X1781028Y831641D02*
G03X1787953Y844772I-30737J24602D01*
G01X1781028Y831641D02*
G03X1814839I16906J-13531D01*
G01X1781028D02*
G03X1814838I16905J-13531D01*
G01X1807913Y844772D02*
G03X1787953I-9980J-3040D01*
G01X1807914D02*
G03X1787953I-9980J-3039D01*
G01X1781028Y1284397D02*
G03X1814839I16906J-13531D01*
G01X1781028D02*
G03X1814838I16905J-13531D01*
G01X1807913Y1297528D02*
G03X1814839Y1284397I37661J11473D01*
G01X1807914Y1297528D02*
G03X1814838Y1284397I37663J11469D01*
G01X1807913Y1297528D02*
G03X1787953I-9980J-3040D01*
G01X1781028Y1284397D02*
G03X1787953Y1297528I-30737J24602D01*
G01X1781028Y1284397D02*
G03X1787953Y1297528I-30737J24602D01*
G01X1807914D02*
G03X1787953I-9980J-3040D01*
G01X1911220Y0D02*
G03Y-7874I0J-3937D01*
G01Y0D02*
G03Y-7874I0J-3937D01*
G01X1880512D02*
G03Y0I0J3937D01*
G01Y-7874D02*
G03Y0I0J3937D01*
G01X1930906Y1382677D02*
X1895276D01*
G01D02*
G03Y1374803I0J-3937D01*
G01X1930906Y1382677D02*
X1895276D01*
G01D02*
G03Y1374803I0J-3937D01*
G01X1864567D02*
G03Y1382677I0J3937D01*
G01Y1374803D02*
G03Y1382677I0J3937D01*
G01X1919843Y-152756D02*
G03X1934843Y-137756I0J15000D01*
G01X1919843Y-152756D02*
G03X1934843Y-137756I0J15000D01*
G01Y-11811D02*
Y-137756D01*
G01Y-11811D02*
Y-137756D01*
G01X1930906Y0D02*
G03X1934843Y3937I0J3937D01*
G01X1930906Y0D02*
G03X1934843Y3937I0J3937D01*
G01Y-11811D02*
G03X1930906Y-7874I-3937J0D01*
G01X1934843Y-11811D02*
G03X1930906Y-7874I-3937J0D01*
G01X1911220D02*
X1930906D01*
G01X1911220D02*
X1930906D01*
G01X1934843Y1370866D02*
Y3937D01*
G01D02*
Y1370866D01*
G01D02*
G03X1930906Y1374803I-3937J0D01*
G01X1934843Y1370866D02*
G03X1930906Y1374803I-3937J0D01*
G01Y1382677D02*
G03X1934843Y1386614I0J3937D01*
G01X1930906Y1382677D02*
G03X1934843Y1386614I0J3937D01*
G01D02*
Y1643268D01*
G01Y1386614D02*
Y1643268D01*
G01D02*
G03X1919843Y1658268I-15000J0D01*
G01X1934843Y1643268D02*
G03X1919843Y1658268I-15000J0D01*
G54D12*
G01X34250Y1176350D02*
X19712D01*
G01X146470Y1173600D02*
X36848D01*
G01X35900Y1178000D02*
X34250Y1176350D01*
G01X395000Y1178000D02*
X35900D01*
G01X248766Y1131400D02*
X39325D01*
G01X39425Y1226200D02*
X725576D01*
G01X726488Y1224000D02*
X31500D01*
G01X39825Y1232700D02*
X267900D01*
G01X37225Y1230100D02*
X39825Y1232700D01*
G01X53273Y1347459D02*
X507004D01*
G01X41381Y1335567D02*
X53273Y1347459D01*
G01X51552Y1342400D02*
X45518Y1336366D01*
G01X278100Y1342400D02*
X51552D01*
G01X181600Y1086900D02*
X148400D01*
G01X152370Y1167700D02*
X146470Y1173600D01*
G01X373450Y1167700D02*
X152370D01*
G01X148800Y1229300D02*
X148300Y1228800D01*
G01X270200Y1229300D02*
X148800D01*
G01X163559Y1345259D02*
X507916D01*
G01X163500Y1345200D02*
X163559Y1345259D01*
G01X200300Y922800D02*
X199900Y923200D01*
G01X670636Y922800D02*
X200300D01*
G01X188600Y1079900D02*
X181600Y1086900D01*
G01X223600Y1079900D02*
X188600D01*
G01X195100Y1107304D02*
Y1096800D01*
G01X198896Y1111100D02*
X195100Y1107304D01*
G01X445388Y1111100D02*
X198896D01*
G01X223100Y920600D02*
X671548D01*
G01X239600Y986200D02*
X239000Y985600D01*
G01X672156Y1005700D02*
X261100D01*
G01X268888Y986200D02*
X239600D01*
G01X246800Y1002400D02*
X443588D01*
G01X244600Y1004600D02*
X246800Y1002400D01*
G01X255437Y993437D02*
X252100Y990100D01*
G01X556675Y993437D02*
X255437D01*
G01X237700Y1065800D02*
X223600Y1079900D01*
G01X270588Y1065800D02*
X237700D01*
G01X435289Y1120500D02*
X264864D01*
G01X264193Y1115973D02*
X248766Y1131400D01*
G01X495302Y1115973D02*
X264193D01*
G01X304800Y75300D02*
X303000Y73500D01*
G01X328600Y75300D02*
X304800D01*
G01X293598Y420500D02*
X291601Y418503D01*
G01X446700Y420500D02*
X293598D01*
G01X283788Y981700D02*
X869008D01*
G01X281588Y983900D02*
X283788Y981700D01*
G01X269700Y983900D02*
X281588D01*
G01X268100Y982300D02*
X269700Y983900D01*
G01X291600Y975800D02*
X871796D01*
G01X288200Y979200D02*
X291600Y975800D01*
G01X283176Y979200D02*
X288200D01*
G01X280676Y981700D02*
X283176Y979200D01*
G01X273300Y981700D02*
X280676D01*
G01X284700Y983900D02*
X281800Y986800D01*
G01X870500Y983900D02*
X284700D01*
G01X269488Y986800D02*
X268888Y986200D01*
G01X281800Y986800D02*
X269488D01*
G01X293242Y1033000D02*
X281200D01*
G01X293890Y1033648D02*
X293242Y1033000D01*
G01X760924Y1033648D02*
X293890D01*
G01X280800Y1011900D02*
X402897D01*
G01X293744Y1036744D02*
X281500D01*
G01X294288Y1036200D02*
X293744Y1036744D01*
G01X760364Y1036200D02*
X294288D01*
G01X273600Y1065700D02*
X271100Y1063200D01*
G01X431300Y1065700D02*
X273600D01*
G01X272688Y1067900D02*
X270588Y1065800D01*
G01X295000Y1067900D02*
X272688D01*
G01X297700Y1070600D02*
X295000Y1067900D01*
G01X311800Y1070600D02*
X297700D01*
G01X314500Y1067900D02*
X311800Y1070600D01*
G01X282536Y1235536D02*
X652836D01*
G01X276100Y1229100D02*
X282536Y1235536D01*
G01X278636Y1237736D02*
X270200Y1229300D01*
G01X651636Y1237736D02*
X278636D01*
G01X275636Y1240436D02*
X651136D01*
G01X267900Y1232700D02*
X275636Y1240436D01*
G01X287300Y1333200D02*
X278100Y1342400D01*
G01X295224Y1333200D02*
X287300D01*
G01X295287Y1333137D02*
X295224Y1333200D01*
G01X296913Y1333137D02*
X295287D01*
G01X296964Y1333188D02*
X296913Y1333137D01*
G01X560674Y1333188D02*
X296964D01*
G01X286100Y1349659D02*
X506092D01*
G01X283700Y1328300D02*
X562418D01*
G01X296337Y1334863D02*
X296100Y1335100D01*
G01X559980Y1334863D02*
X296337D01*
G01X282300Y1330700D02*
X279900Y1328300D01*
G01X561706Y1330700D02*
X282300D01*
G01X296104Y1339496D02*
X295900Y1339700D01*
G01X520104Y1339496D02*
X296104D01*
G01X298333Y1337367D02*
X292600D01*
G01X299162Y1336538D02*
X298333Y1337367D01*
G01X559286Y1336538D02*
X299162D01*
G01X337641Y124295D02*
Y114910D01*
G01X353381Y97940D02*
X415910Y160469D01*
G01X346842Y97940D02*
X353381D01*
G01X341932Y93030D02*
X346842Y97940D01*
G01X336522Y93030D02*
X341932D01*
G01X334947Y94605D02*
X336522Y93030D01*
G01X345133Y114133D02*
X335081Y104081D01*
G01X345133Y114936D02*
Y114133D01*
G01X348478Y118281D02*
X345133Y114936D01*
G01X352899Y100234D02*
X414809Y162144D01*
G01X344265Y100234D02*
X352899D01*
G01X339219Y95188D02*
X344265Y100234D01*
G01X354896Y89276D02*
X405959Y140339D01*
G01X351141Y89276D02*
X354896D01*
G01X344304Y82439D02*
X351141Y89276D01*
G01X348125Y104794D02*
X443330Y199999D01*
G01X347715Y104794D02*
X348125D01*
G01X345321Y102400D02*
X347715Y104794D01*
G01X359200Y73418D02*
X361776Y70842D01*
G01X359200Y85545D02*
Y73418D01*
G01X412319Y138664D02*
X359200Y85545D01*
G01X335400Y68500D02*
X328600Y75300D01*
G01X369747Y68500D02*
X335400D01*
G01X355890Y117704D02*
X353001Y114815D01*
G01X354736Y91545D02*
X409685Y146494D01*
G01X354692Y91545D02*
X354736D01*
G01X354098Y90951D02*
X354692Y91545D01*
G01X348450Y90951D02*
X354098D01*
G01X339914Y82415D02*
X348450Y90951D01*
G01X354042Y93220D02*
X408991Y148169D01*
G01X349892Y93220D02*
X354042D01*
G01X347647Y95465D02*
X349892Y93220D01*
G01X347647Y95614D02*
Y95465D01*
G01X353834Y95788D02*
X416840Y158794D01*
G01X351416Y95788D02*
X353834D01*
G01X341596Y128250D02*
X337641Y124295D01*
G01X356078Y128250D02*
X341596D01*
G01X455550Y227722D02*
X356078Y128250D01*
G01X348478Y118354D02*
Y118281D01*
G01X349628Y119504D02*
X348478Y118354D01*
G01X349701Y119504D02*
X349628D01*
G01X456244Y226047D02*
X349701Y119504D01*
G01X358666Y117704D02*
X355890D01*
G01X443373Y202411D02*
X358666Y117704D01*
G01X336900Y925300D02*
X432068D01*
G01X335300Y926900D02*
X336900Y925300D01*
G01X338500Y973500D02*
X870984D01*
G01X337100Y972100D02*
X338500Y973500D01*
G01X761588Y1031200D02*
X350673D01*
G01X557587Y995637D02*
X344737D01*
G01X432212Y1067900D02*
X314500D01*
G01X406358Y1175800D02*
X331679D01*
G01X618100Y1216700D02*
X315500D01*
G01X414515Y132500D02*
X377944Y95929D01*
G01X429647Y128400D02*
X369747Y68500D01*
G01X423249Y130825D02*
X377144Y84720D01*
G01X405959Y140339D02*
X491762D01*
G01X409685Y146494D02*
X495011D01*
G01X408991Y148169D02*
X494317D01*
G01X403660Y1012663D02*
X433100D01*
G01X402897Y1011900D02*
X403660Y1012663D01*
G01X411334Y1010700D02*
X408672Y1008038D01*
G01X457316Y1118173D02*
X388888D01*
G01X379050Y1173300D02*
X373450Y1167700D01*
G01X405526Y1173300D02*
X379050D01*
G01X407650Y1171176D02*
X405526Y1173300D01*
G01X436299Y1171176D02*
X407650D01*
G01X397175Y1180175D02*
X395000Y1178000D01*
G01X408782Y1173376D02*
X406358Y1175800D01*
G01X435387Y1173376D02*
X408782D01*
G01X460960Y1180175D02*
X397175D01*
G01X398527Y1233336D02*
X653962D01*
G01X415910Y160469D02*
X629690D01*
G01X464400Y132500D02*
X414515D01*
G01X414809Y162144D02*
X626605D01*
G01X492456Y138664D02*
X412319D01*
G01X456047Y128400D02*
X429647D01*
G01X461700Y122747D02*
X456047Y128400D01*
G01X462575Y130825D02*
X423249D01*
G01X416840Y158794D02*
X638165D01*
G01X454818Y199999D02*
X477516Y222697D01*
G01X443330Y199999D02*
X454818D01*
G01X454718Y202411D02*
X443373D01*
G01X476679Y224372D02*
X454718Y202411D01*
G01X456209Y227722D02*
X455550D01*
G01X496192Y267705D02*
X456209Y227722D01*
G01X642714Y226047D02*
X456244D01*
G01X456190Y354105D02*
X534905D01*
G01X449075Y422875D02*
X446700Y420500D01*
G01X680694Y422875D02*
X449075D01*
G01X418600Y445462D02*
X830122D01*
G01X452800Y420912D02*
X680288D01*
G01X421700Y450200D02*
X865221D01*
G01X708924Y475900D02*
X447533D01*
G01X437368Y930600D02*
X551300D01*
G01X432068Y925300D02*
X437368Y930600D01*
G01X445582Y925352D02*
X670076D01*
G01X452280Y970900D02*
X449137Y967757D01*
G01X870472Y970900D02*
X452280D01*
G01X433237Y1015682D02*
X432657Y1015102D01*
G01X433237Y1019213D02*
Y1015682D01*
G01X436886Y1022862D02*
X433237Y1019213D01*
G01X685083Y1022862D02*
X436886D01*
G01X444288Y1003100D02*
X571288D01*
G01X443588Y1002400D02*
X444288Y1003100D01*
G01X441624Y1021187D02*
X685777D01*
G01X433100Y1012663D02*
X441624Y1021187D01*
G01X431562Y1019869D02*
X429613Y1017920D01*
G01X431562Y1019907D02*
Y1019869D01*
G01X436192Y1024537D02*
X431562Y1019907D01*
G01X684388Y1024537D02*
X436192D01*
G01X777500Y1010700D02*
X411334D01*
G01X445000Y1000700D02*
X442600Y998300D01*
G01X557100Y1000700D02*
X445000D01*
G01X433200Y1063800D02*
X431300Y1065700D01*
G01X465620Y1063800D02*
X433200D01*
G01X414790Y1052410D02*
X413000Y1054200D01*
G01X488330Y1052410D02*
X414790D01*
G01X433586Y1066526D02*
X432212Y1067900D01*
G01X465234Y1066526D02*
X433586D01*
G01X445715Y1110773D02*
X445388Y1111100D01*
G01X594719Y1110773D02*
X445715D01*
G01X468768Y1129625D02*
X457316Y1118173D01*
G01X446614Y1131825D02*
X435289Y1120500D01*
G01X440894Y1175771D02*
X436299Y1171176D01*
G01X507860Y1175771D02*
X440894D01*
G01X683699Y1131825D02*
X446614D01*
G01X439984Y1177973D02*
X435387Y1173376D01*
G01X508770Y1177973D02*
X439984D01*
G01X478757Y1169400D02*
X441400D01*
G01X727400Y1221800D02*
X416900D01*
G01X412400Y1326300D02*
X412300Y1326200D01*
G01X563530Y1326300D02*
X412400D01*
G01X415422Y1352000D02*
X505321D01*
G01X465157Y114764D02*
X461700Y118221D01*
G01X469228Y113843D02*
Y124172D01*
G01X472244Y110827D02*
X469228Y113843D01*
G01X474507Y122393D02*
X464400Y132500D01*
G01X474507Y118507D02*
Y122393D01*
G01X472339Y116339D02*
X474507Y118507D01*
G01X472244Y116339D02*
X472339D01*
G01X501647Y150224D02*
X578229D01*
G01X491762Y140339D02*
X501647Y150224D01*
G01X502341Y148549D02*
X492456Y138664D01*
G01X577535Y148549D02*
X502341D01*
G01X461700Y118221D02*
Y122747D01*
G01X469228Y124172D02*
X462575Y130825D01*
G01X500416Y151899D02*
X578923D01*
G01X495011Y146494D02*
X500416Y151899D01*
G01X499722Y153574D02*
X579617D01*
G01X494317Y148169D02*
X499722Y153574D01*
G01X477516Y222697D02*
X648153D01*
G01X644851Y224372D02*
X476679D01*
G01X553742Y267705D02*
X496192D01*
G01X496323Y495665D02*
X481533Y480875D01*
G01X878435Y495665D02*
X496323D01*
G01X469099Y1014301D02*
X465200Y1018200D01*
G01X777599Y1014301D02*
X469099D01*
G01X599993Y1051900D02*
X506500D01*
G01X467156Y1065336D02*
X465620Y1063800D01*
G01X630344Y1065336D02*
X467156D01*
G01X490120Y1054200D02*
X488330Y1052410D01*
G01X600805Y1054200D02*
X490120D01*
G01X466245Y1067537D02*
X465234Y1066526D01*
G01X629433Y1067537D02*
X466245D01*
G01X682787Y1129625D02*
X468768D01*
G01X503675Y1124346D02*
X495302Y1115973D01*
G01X542848Y1124346D02*
X503675D01*
G01X482928Y1173571D02*
X478757Y1169400D01*
G01X506948Y1173571D02*
X482928D01*
G01X511862Y1168657D02*
X506948Y1173571D01*
G01X460962Y1180173D02*
X460960Y1180175D01*
G01X462786Y1180173D02*
X460962D01*
G01X462788Y1180175D02*
X462786Y1180173D01*
G01X475508Y1180175D02*
X462788D01*
G01X478833Y1183500D02*
X475508Y1180175D01*
G01X485800Y1183500D02*
X478833D01*
G01X489127Y1180173D02*
X485800Y1183500D01*
G01X597365Y1180173D02*
X489127D01*
G01X507004Y1347459D02*
X512771Y1353226D01*
G01X506092Y1349659D02*
X511859Y1355426D01*
G01X505321Y1352000D02*
X510947Y1357626D01*
G01X554700Y927200D02*
X668812D01*
G01X551300Y930600D02*
X554700Y927200D01*
G01X531500Y1029000D02*
X530800Y1028300D01*
G01X762500Y1029000D02*
X531500D01*
G01X545927Y1127425D02*
X542848Y1124346D01*
G01X681875Y1127425D02*
X545927D01*
G01X512774Y1170857D02*
X507860Y1175771D01*
G01X594273Y1170857D02*
X512774D01*
G01X606367Y1136700D02*
X509037D01*
G01X513686Y1173057D02*
X508770Y1177973D01*
G01X593361Y1173057D02*
X513686D01*
G01X595185Y1168657D02*
X511862D01*
G01X522867Y1231097D02*
X654835D01*
G01X564442Y1324100D02*
X520600D01*
G01X551015Y1357700D02*
X656855D01*
G01X546541Y1353226D02*
X551015Y1357700D01*
G01X512771Y1353226D02*
X546541D01*
G01X549900Y1359900D02*
X657767D01*
G01X545426Y1355426D02*
X549900Y1359900D01*
G01X511859Y1355426D02*
X545426D01*
G01X548988Y1362100D02*
X658679D01*
G01X544514Y1357626D02*
X548988Y1362100D01*
G01X510947Y1357626D02*
X544514D01*
G01X551927Y1355500D02*
X655943D01*
G01X548171Y1351744D02*
X551927Y1355500D01*
G01X548171Y1351743D02*
Y1351744D01*
G01X547454Y1351026D02*
X548171Y1351743D01*
G01X513683Y1351026D02*
X547454D01*
G01X507916Y1345259D02*
X513683Y1351026D01*
G01X535500Y1364500D02*
X826652D01*
G01X531000Y1360000D02*
X535500Y1364500D01*
G01X518397Y1360000D02*
X531000D01*
G01X521387Y1338213D02*
X520104Y1339496D01*
G01X558592Y1338213D02*
X521387D01*
G01X583633Y144819D02*
X668430D01*
G01X581672Y146780D02*
X583633Y144819D01*
G01X581672Y146781D02*
Y146780D01*
G01X578229Y150224D02*
X581672Y146781D01*
G01X579997Y146087D02*
X577535Y148549D01*
G01X579997Y146086D02*
Y146087D01*
G01X581958Y144125D02*
X579997Y146086D01*
G01X581958Y144124D02*
Y144125D01*
G01X582938Y143144D02*
X581958Y144124D01*
G01X669706Y143144D02*
X582938D01*
G01X584327Y146494D02*
X647689D01*
G01X583347Y147474D02*
X584327Y146494D01*
G01X583347Y147475D02*
Y147474D01*
G01X578923Y151899D02*
X583347Y147475D01*
G01X585022Y148169D02*
X633565D01*
G01X579617Y153574D02*
X585022Y148169D01*
G01X572100Y999400D02*
X571400Y1000100D01*
G01X675192Y999400D02*
X572100D01*
G01X571388Y1003200D02*
X672732D01*
G01X571288Y1003100D02*
X571388Y1003200D01*
G01X558412Y991700D02*
X556675Y993437D01*
G01X676828Y991700D02*
X558412D01*
G01X559324Y993900D02*
X557587Y995637D01*
G01X675916Y993900D02*
X559324D01*
G01X561700Y996100D02*
X557100Y1000700D01*
G01X675004Y996100D02*
X561700D01*
G01X600887Y1051006D02*
X599993Y1051900D01*
G01X622238Y1051006D02*
X600887D01*
G01X601799Y1053206D02*
X600805Y1054200D01*
G01X621326Y1053206D02*
X601799D01*
G01X606788Y1122842D02*
X594719Y1110773D01*
G01X599490Y1176074D02*
X594273Y1170857D01*
G01X633637Y1176074D02*
X599490D01*
G01X598578Y1178274D02*
X593361Y1173057D01*
G01X632725Y1178274D02*
X598578D01*
G01X600402Y1173874D02*
X595185Y1168657D01*
G01X634549Y1173874D02*
X600402D01*
G01X602860Y1168780D02*
X600640Y1171000D01*
G01X632567Y1168780D02*
X602860D01*
G01X600591Y1183399D02*
X597365Y1180173D01*
G01X644448Y1183399D02*
X600591D01*
G01X776483Y1214456D02*
X592400D01*
G01X566916Y1326574D02*
X564442Y1324100D01*
G01X560686Y1333200D02*
X560674Y1333188D01*
G01X561094Y1333200D02*
X560686D01*
G01X563194Y1335300D02*
X561094Y1333200D01*
G01X646874Y1335300D02*
X563194D01*
G01X566004Y1328774D02*
X563530Y1326300D01*
G01X644064Y1328774D02*
X566004D01*
G01X565092Y1330974D02*
X644976D01*
G01X562418Y1328300D02*
X565092Y1330974D01*
G01X562454Y1337337D02*
X559980Y1334863D01*
G01X647614Y1337337D02*
X562454D01*
G01X564180Y1333174D02*
X561706Y1330700D01*
G01X645888Y1333174D02*
X564180D01*
G01X643152Y1326574D02*
X566916D01*
G01X561066Y1340687D02*
X558592Y1338213D01*
G01X649002Y1340687D02*
X561066D01*
G01X561760Y1339012D02*
X559286Y1336538D01*
G01X648308Y1339012D02*
X561760D01*
G01X629690Y160469D02*
X688517Y219296D01*
G01X626605Y162144D02*
X685929Y221468D01*
G01X647689Y146494D02*
X695903Y194708D01*
G01X633565Y148169D02*
X675660Y190264D01*
G01X638165Y158794D02*
X706665Y227294D01*
G01X657885Y241218D02*
X642714Y226047D01*
G01X648153Y222697D02*
X663416Y237960D01*
G01X660650Y240171D02*
X644851Y224372D01*
G01X612000Y502300D02*
X616060Y506360D01*
G01D02*
X875760D01*
G01X645200Y1067801D02*
Y1067800D01*
G01X664772Y1087373D02*
X645200Y1067801D01*
G01X660805Y1089573D02*
X622238Y1051006D01*
G01X658981Y1093973D02*
X630344Y1065336D01*
G01X659893Y1091773D02*
X621326Y1053206D01*
G01X658069Y1096173D02*
X629433Y1067537D01*
G01X682258Y1122842D02*
X606788D01*
G01X639039Y1170100D02*
X636803Y1167864D01*
G01X658900Y1170100D02*
X639039D01*
G01X685523Y1136225D02*
X632603D01*
G01X635763Y1178200D02*
X633637Y1176074D01*
G01X749436Y1178200D02*
X635763D01*
G01X609042Y1134025D02*
X606367Y1136700D01*
G01X684611Y1134025D02*
X609042D01*
G01X634851Y1180400D02*
X632725Y1178274D01*
G01X636675Y1176000D02*
X634549Y1173874D01*
G01X748524Y1176000D02*
X636675D01*
G01X637587Y1173800D02*
X632567Y1168780D01*
G01X739200Y1173800D02*
X637587D01*
G01X621000Y1219600D02*
X618100Y1216700D01*
G01X728500Y1219600D02*
X621000D01*
G01X776215Y1217300D02*
X627632D01*
G01X648653Y1187604D02*
X644448Y1183399D01*
G01X746256Y1187604D02*
X648653D01*
G01X644561Y1180400D02*
X634851D01*
G01X649281Y1185120D02*
X644561Y1180400D01*
G01X745628Y1185120D02*
X649281D01*
G01X689511Y1275611D02*
X651636Y1237736D01*
G01X651136Y1240436D02*
X688511Y1277811D01*
G01X688038Y1284800D02*
X644064Y1328774D01*
G01X644976Y1330974D02*
X688950Y1287000D01*
G01X687126Y1282600D02*
X643152Y1326574D01*
G01X690674Y1291500D02*
X646874Y1335300D01*
G01X691151Y1293800D02*
X647614Y1337337D01*
G01X689862Y1289200D02*
X645888Y1333174D01*
G01X692539Y1297150D02*
X649002Y1340687D01*
G01X691845Y1295475D02*
X648308Y1339012D01*
G01X668430Y144819D02*
X717331Y193720D01*
G01X719591Y193029D02*
X669706Y143144D01*
G01X699161Y194708D02*
X702025Y197572D01*
G01X695903Y194708D02*
X699161D01*
G01X690077Y200731D02*
X722371Y233025D01*
G01X690077Y195004D02*
Y200731D01*
G01X685337Y190264D02*
X690077Y195004D01*
G01X675660Y190264D02*
X685337D01*
G01X699774Y237663D02*
Y299498D01*
G01X688517Y226406D02*
X699774Y237663D01*
G01X688517Y219296D02*
Y226406D01*
G01X657885Y291777D02*
Y241218D01*
G01X685929Y221468D02*
Y293751D01*
G01X663416Y237960D02*
Y285852D01*
G01X660650Y289998D02*
Y240171D01*
G01X699774Y299498D02*
X744465Y344189D01*
G01X723994Y357886D02*
X657885Y291777D01*
G01X685929Y293751D02*
X739009Y346831D01*
G01X663416Y285852D02*
X729119Y351555D01*
G01X724530Y353878D02*
X660650Y289998D01*
G01X725074Y378495D02*
X680694Y422875D01*
G01X680288Y420912D02*
X741289Y359911D01*
G01X665326Y508500D02*
X658646Y515180D01*
G01X839500Y508500D02*
X665326D01*
G01X668812Y927200D02*
X703912Y962300D01*
G01X671548Y920600D02*
X706648Y955700D01*
G01X705736Y957900D02*
X670636Y922800D01*
G01X668600Y930100D02*
X658574D01*
G01X703000Y964500D02*
X668600Y930100D01*
G01X670076Y925352D02*
X704824Y960100D01*
G01X680184Y944796D02*
X677457D01*
G01X703019Y967631D02*
X680184Y944796D01*
G01X674979Y1002299D02*
X674300Y1001620D01*
G01X786682Y1002299D02*
X674979D01*
G01X673155Y1006699D02*
X672156Y1005700D01*
G01X784858Y1006699D02*
X673155D01*
G01X685084Y1022863D02*
X685083Y1022862D01*
G01X763606Y1022863D02*
X685084D01*
G01X675891Y1000099D02*
X675192Y999400D01*
G01X787594Y1000099D02*
X675891D01*
G01X674031Y1004499D02*
X785770D01*
G01X672732Y1003200D02*
X674031Y1004499D01*
G01X685778Y1021188D02*
X762912D01*
G01X685777Y1021187D02*
X685778Y1021188D01*
G01X684389Y1024538D02*
X684388Y1024537D01*
G01X764313Y1024538D02*
X684389D01*
G01X678427Y993299D02*
X676828Y991700D01*
G01X861811Y993299D02*
X678427D01*
G01X763500Y1026500D02*
X682200D01*
G01X665599Y1016501D02*
X663800Y1018300D01*
G01X778511Y1016501D02*
X665599D01*
G01X677515Y995499D02*
X675916Y993900D01*
G01X862723Y995499D02*
X677515D01*
G01X676603Y997699D02*
X675004Y996100D01*
G01X868177Y997699D02*
X676603D01*
G01X718507Y1048805D02*
X679939Y1087373D01*
G01X719418Y1051006D02*
X680851Y1089573D01*
G01X710044Y1066604D02*
X682675Y1093973D01*
G01X720330Y1053206D02*
X681763Y1091773D01*
G01X710956Y1068804D02*
X683587Y1096173D01*
G01X694896Y1110204D02*
X682258Y1122842D01*
G01X725076Y1110204D02*
X694896D01*
G01X696595Y1125153D02*
X685523Y1136225D01*
G01X798293Y1125153D02*
X696595D01*
G01X696708Y1115704D02*
X682787Y1129625D01*
G01X798180Y1115704D02*
X696708D01*
G01X679939Y1087373D02*
X664772D01*
G01X680851Y1089573D02*
X660805D01*
G01X697620Y1117904D02*
X683699Y1131825D01*
G01X797268Y1117904D02*
X697620D01*
G01X698532Y1120104D02*
X684611Y1134025D01*
G01X796356Y1120104D02*
X698532D01*
G01X682675Y1093973D02*
X658981D01*
G01X681763Y1091773D02*
X659893D01*
G01X696896Y1112404D02*
X681875Y1127425D01*
G01X725988Y1112404D02*
X696896D01*
G01X683587Y1096173D02*
X658069D01*
G01X660300Y1168700D02*
X658900Y1170100D01*
G01X741300Y1168700D02*
X660300D01*
G01X690099Y1272799D02*
X725678D01*
G01X652836Y1235536D02*
X690099Y1272799D01*
G01X728174Y1275611D02*
X689511D01*
G01X691183Y1270557D02*
X722790D01*
G01X653962Y1233336D02*
X691183Y1270557D01*
G01X691165Y1267427D02*
X720446D01*
G01X654835Y1231097D02*
X691165Y1267427D01*
G01X1111421Y1291500D02*
X690674D01*
G01X738082Y1284800D02*
X688038D01*
G01X688950Y1287000D02*
X738994D01*
G01X843201Y1293800D02*
X691151D01*
G01X739906Y1289200D02*
X689862D01*
G01X688511Y1277811D02*
X731500D01*
G01X666100Y1280200D02*
X664000Y1278100D01*
G01X736458Y1280200D02*
X666100D01*
G01X737170Y1282600D02*
X687126D01*
G01X840550Y1297150D02*
X692539D01*
G01X842506Y1295475D02*
X691845D01*
G01X667055Y1347500D02*
X822100D01*
G01X656855Y1357700D02*
X667055Y1347500D01*
G01X667967Y1349700D02*
X821188D01*
G01X657767Y1359900D02*
X667967Y1349700D01*
G01X673000Y1354100D02*
X819364D01*
G01X668879Y1351900D02*
X820276D01*
G01X658679Y1362100D02*
X668879Y1351900D01*
G01X666143Y1345300D02*
X823200D01*
G01X655943Y1355500D02*
X666143Y1345300D01*
G01X717331Y193720D02*
Y215346D01*
G01X719591Y215237D02*
Y193029D01*
G01X706074Y211989D02*
X724046Y229961D01*
G01X706074Y205373D02*
Y211989D01*
G01X702025Y201324D02*
X706074Y205373D01*
G01X702025Y197572D02*
Y201324D01*
G01X737870Y235885D02*
Y299388D01*
G01X717331Y215346D02*
X737870Y235885D01*
G01X739545Y235191D02*
X719591Y215237D01*
G01X739545Y298694D02*
Y235191D01*
G01X724046Y229961D02*
Y292763D01*
G01X722371Y233025D02*
Y293457D01*
G01X706665Y227294D02*
Y300957D01*
G01X737870Y299388D02*
X774450Y335968D01*
G01X775144Y334293D02*
X739545Y298694D01*
G01X724141Y302931D02*
X759653Y338443D01*
G01X724141Y292858D02*
Y302931D01*
G01X724046Y292763D02*
X724141Y292858D01*
G01X722466Y303759D02*
X758825Y340118D01*
G01X722466Y293552D02*
Y303759D01*
G01X722371Y293457D02*
X722466Y293552D01*
G01X706665Y300957D02*
X747939Y342231D01*
G01X744465Y344189D02*
X904809D01*
G01X745705Y345864D02*
X903245D01*
G01X744738Y346831D02*
X745705Y345864D01*
G01X739009Y346831D02*
X744738D01*
G01X729119Y351555D02*
X898622D01*
G01X873944Y353878D02*
X724530D01*
G01X747939Y342231D02*
X908105D01*
G01X884806Y357886D02*
X723994D01*
G01X887500Y378495D02*
X725074D01*
G01X741289Y359911D02*
X886289D01*
G01X723639Y490615D02*
X708924Y475900D01*
G01X875385Y490615D02*
X723639D01*
G01X703912Y962300D02*
X760788D01*
G01X706648Y955700D02*
X758052D01*
G01X870629Y967631D02*
X703019D01*
G01X758964Y957900D02*
X705736D01*
G01X761700Y964500D02*
X703000D01*
G01X704824Y960100D02*
X759876D01*
G01X737391Y1048805D02*
X718507D01*
G01X747986Y1059400D02*
X737391Y1048805D01*
G01X906331Y1059400D02*
X747986D01*
G01X736480Y1051006D02*
X719418D01*
G01X747297Y1061823D02*
X736480Y1051006D01*
G01X908477Y1061823D02*
X747297D01*
G01X916969Y1066604D02*
X710044D01*
G01X735568Y1053206D02*
X720330D01*
G01X746766Y1064404D02*
X735568Y1053206D01*
G01X913799Y1064404D02*
X746766D01*
G01X919355Y1068804D02*
X710956D01*
G01X726176Y1109104D02*
X725076Y1110204D01*
G01X797804Y1109104D02*
X726176D01*
G01X727088Y1111304D02*
X725988Y1112404D01*
G01X796892Y1111304D02*
X727088D01*
G01X749401Y1160599D02*
X741300Y1168700D01*
G01X760437Y1167199D02*
X749436Y1178200D01*
G01X759525Y1164999D02*
X748524Y1176000D01*
G01X750201Y1162799D02*
X739200Y1173800D01*
G01X750800Y1241900D02*
X728500Y1219600D01*
G01X725576Y1226200D02*
X748514Y1249138D01*
G01X751210Y1182650D02*
X746256Y1187604D01*
G01X749426Y1246938D02*
X726488Y1224000D01*
G01X761349Y1169399D02*
X745628Y1185120D01*
G01X750338Y1244738D02*
X727400Y1221800D01*
G01X751182Y1271700D02*
X738082Y1284800D01*
G01X748514Y1249138D02*
X946038D01*
G01X749858Y1266800D02*
X736458Y1280200D01*
G01X750570Y1269200D02*
X737170Y1282600D01*
G01X738994Y1287000D02*
X752094Y1273900D01*
G01X753006Y1276100D02*
X739906Y1289200D01*
G01X790093Y336098D02*
X911072D01*
G01X789963Y335968D02*
X790093Y336098D01*
G01X774450Y335968D02*
X789963D01*
G01X790657Y334293D02*
X775144D01*
G01X790787Y334423D02*
X790657Y334293D01*
G01X873430Y334423D02*
X790787D01*
G01X759653Y338443D02*
X909850D01*
G01X758825Y340118D02*
X908606D01*
G01X790246Y366000D02*
X891631D01*
G01X789739Y365493D02*
X790246Y366000D01*
G01X875848Y959300D02*
X780800D01*
G01X773199Y949889D02*
X875923D01*
G01X760788Y962300D02*
X773199Y949889D01*
G01X770463Y943289D02*
X873187D01*
G01X758052Y955700D02*
X770463Y943289D01*
G01X771375Y945489D02*
X758964Y957900D01*
G01X874099Y945489D02*
X771375D01*
G01X774111Y952089D02*
X761700Y964500D01*
G01X876835Y952089D02*
X774111D01*
G01X776400Y956500D02*
X875536D01*
G01X772287Y947689D02*
X875011D01*
G01X759876Y960100D02*
X772287Y947689D01*
G01X786683Y1002300D02*
X786682Y1002299D01*
G01X869800Y1002300D02*
X786683D01*
G01X784859Y1006700D02*
X784858Y1006699D01*
G01X909953Y1006700D02*
X784859D01*
G01X766331Y1020138D02*
X763606Y1022863D01*
G01X780021Y1020138D02*
X766331D01*
G01X780521Y1019638D02*
X780021Y1020138D01*
G01X892138Y1019638D02*
X780521D01*
G01X787595Y1000100D02*
X787594Y1000099D01*
G01X868888Y1000100D02*
X787595D01*
G01X914659Y1016000D02*
X786800D01*
G01X785771Y1004500D02*
X898200D01*
G01X785770Y1004499D02*
X785771Y1004500D01*
G01X762318Y1035042D02*
X760924Y1033648D01*
G01X779826Y1017963D02*
X915473D01*
G01X779326Y1018463D02*
X779826Y1017963D01*
G01X767025Y1018463D02*
X779326D01*
G01X767024Y1018462D02*
X767025Y1018463D01*
G01X765638Y1018462D02*
X767024D01*
G01X762912Y1021188D02*
X765638Y1018462D01*
G01X766814Y1022037D02*
X764313Y1024538D01*
G01X892168Y1022037D02*
X766814D01*
G01X763885Y1030385D02*
X762500Y1029000D01*
G01X942689Y1030385D02*
X763885D01*
G01X765100Y1028100D02*
X763500Y1026500D01*
G01X941862Y1028100D02*
X765100D01*
G01X781573Y1013439D02*
X778511Y1016501D01*
G01X914108Y1013439D02*
X781573D01*
G01X780761Y1011139D02*
X777599Y1014301D01*
G01X790565Y1011139D02*
X780761D01*
G01X790566Y1011140D02*
X790565Y1011139D01*
G01X792427Y1011140D02*
X790566D01*
G01X792428Y1011139D02*
X792427Y1011140D01*
G01X912504Y1011139D02*
X792428D01*
G01X779262Y1008938D02*
X777500Y1010700D01*
G01X783946Y1008938D02*
X779262D01*
G01X783947Y1008939D02*
X783946Y1008938D01*
G01X911227Y1008939D02*
X783947D01*
G01X762988Y1032600D02*
X761588Y1031200D01*
G01X943600Y1032600D02*
X762988D01*
G01X891354Y1024000D02*
X784000D01*
G01X761406Y1037242D02*
X760364Y1036200D01*
G01X908060Y1037242D02*
X761406D01*
G01X760300Y1056900D02*
X899152D01*
G01X759500Y1056100D02*
X760300Y1056900D01*
G01X909748Y1035042D02*
X762318D01*
G01X818827Y1130127D02*
X797804Y1109104D01*
G01X816091Y1136727D02*
X797268Y1117904D01*
G01X815179Y1138927D02*
X796356Y1120104D01*
G01X817915Y1132327D02*
X796892Y1111304D01*
G01X769041Y1160599D02*
X749401D01*
G01X779669Y1149971D02*
X769041Y1160599D01*
G01X955118Y1149971D02*
X779669D01*
G01X771977Y1167199D02*
X760437D01*
G01X782605Y1156571D02*
X771977Y1167199D01*
G01X957967Y1156571D02*
X782605D01*
G01X762361Y1171599D02*
X751310Y1182650D01*
G01X773801Y1171599D02*
X762361D01*
G01X784429Y1160971D02*
X773801Y1171599D01*
G01X959791Y1160971D02*
X784429D01*
G01X792263Y1174461D02*
X811084D01*
G01X792264Y1170260D02*
X809252D01*
G01X792263Y1170261D02*
X792264Y1170260D01*
G01X792263Y1178661D02*
X812915D01*
G01X772889Y1169399D02*
X761349D01*
G01X783517Y1158771D02*
X772889Y1169399D01*
G01X958879Y1158771D02*
X783517D01*
G01X770865Y1164999D02*
X759525D01*
G01X781493Y1154371D02*
X770865Y1164999D01*
G01X956942Y1154371D02*
X781493D01*
G01X769953Y1162799D02*
X750201D01*
G01X780581Y1152171D02*
X769953Y1162799D01*
G01X956030Y1152171D02*
X780581D01*
G01X797177Y1189537D02*
X815098D01*
G01X779535Y1193469D02*
X798766Y1212700D01*
G01X793466Y1214900D02*
X1036588D01*
G01X784544Y1205978D02*
X793466Y1214900D01*
G01X791466Y1217100D02*
X1037500D01*
G01X784544Y1210178D02*
X791466Y1217100D01*
G01X779535Y1189269D02*
X800766Y1210500D01*
G01X798615Y1239700D02*
X776215Y1217300D01*
G01X751310Y1182650D02*
X751210D01*
G01X792263Y1182861D02*
X814746D01*
G01X779535Y1180469D02*
X805166Y1206100D01*
G01X813457Y1185337D02*
X797225D01*
G01X789727Y1227700D02*
X776483Y1214456D01*
G01X1111682Y1227700D02*
X789727D01*
G01X779535Y1184669D02*
X803166Y1208300D01*
G01X948900Y1241900D02*
X750800D01*
G01X1077300Y1271700D02*
X751182D01*
G01X752094Y1273900D02*
X1083105D01*
G01X1079500Y1276100D02*
X753006D01*
G01X947500Y1246938D02*
X749426D01*
G01X1084400Y1266800D02*
X749858D01*
G01X1081800Y1269200D02*
X750570D01*
G01X948412Y1244738D02*
X750338D01*
G01X792336Y1319612D02*
Y1319537D01*
G01X830055Y1319612D02*
X792336D01*
G01X785640Y1328043D02*
Y1328370D01*
G01X788753Y1324930D02*
X785640Y1328043D01*
G01X831465Y1324930D02*
X788753D01*
G01X790900Y1327800D02*
X790290Y1328410D01*
G01X830092Y1327800D02*
X790900D01*
G01X833185Y448525D02*
X864517D01*
G01X830122Y445462D02*
X833185Y448525D01*
G01X973244Y1130127D02*
X818827D01*
G01X814268Y1141128D02*
X798293Y1125153D01*
G01X817003Y1134527D02*
X798180Y1115704D01*
G01X977803Y1141128D02*
X814268D01*
G01X975068Y1134527D02*
X817003D01*
G01X975980Y1136727D02*
X816091D01*
G01X976892Y1138927D02*
X815179D01*
G01X811084Y1174461D02*
X828550Y1191927D01*
G01X974156Y1132327D02*
X817915D01*
G01X811238Y1164244D02*
X802036D01*
G01X823384Y1176390D02*
X811238Y1164244D01*
G01X966755Y1176390D02*
X823384D01*
G01X809252Y1170260D02*
X828482Y1189490D01*
G01X812915Y1178661D02*
X829554Y1195300D01*
G01X829461Y1203900D02*
X1029312D01*
G01X815098Y1189537D02*
X829461Y1203900D01*
G01X798766Y1212700D02*
X1034100D01*
G01X800766Y1210500D02*
X1032800D01*
G01X828550Y1191927D02*
X992673D01*
G01X829385Y1197500D02*
X1008139D01*
G01X814746Y1182861D02*
X829385Y1197500D01*
G01X805166Y1206100D02*
X1030976D01*
G01X829820Y1201700D02*
X813457Y1185337D01*
G01X1026264Y1201700D02*
X829820D01*
G01X828482Y1189490D02*
X991998D01*
G01X829554Y1195300D02*
X1007227D01*
G01X803166Y1208300D02*
X1031888D01*
G01X950500Y1239700D02*
X798615D01*
G01X864073Y1314672D02*
X843201Y1293800D01*
G01X849543Y1339100D02*
X830055Y1319612D01*
G01X877400Y1334000D02*
X840550Y1297150D01*
G01X879031Y1332000D02*
X842506Y1295475D01*
G01X822100Y1347500D02*
X863187Y1388587D01*
G01X821188Y1349700D02*
X861988Y1390500D01*
G01X819364Y1354100D02*
X860282Y1395018D01*
G01X820276Y1351900D02*
X861076Y1392700D01*
G01X848398Y1341863D02*
X831465Y1324930D01*
G01X823200Y1345300D02*
X863900Y1386000D01*
G01X826652Y1364500D02*
X859370Y1397218D01*
G01X847155Y1344863D02*
X830092Y1327800D01*
G01X885771Y356921D02*
X884806Y357886D01*
G01X894750Y356921D02*
X885771D01*
G01X881549Y326304D02*
X873430Y334423D01*
G01X873987Y353835D02*
X873944Y353878D01*
G01X875613Y353835D02*
X873987D01*
G01X875678Y353900D02*
X875613Y353835D01*
G01X895877Y353900D02*
X875678D01*
G01X890982Y349498D02*
X901845D01*
G01X891631Y366000D02*
X899159Y373528D01*
G01X886289Y359911D02*
X887100Y359100D01*
G01D02*
X899853Y371853D01*
G01X877600Y454900D02*
X906900Y425600D01*
G01X864517Y448525D02*
X866317Y446725D01*
G01X865221Y450200D02*
X866321Y451300D01*
G01X909357Y456643D02*
X875385Y490615D01*
G01X866276Y454900D02*
X877600D01*
G01X914407Y459693D02*
X878435Y495665D01*
G01X875760Y506360D02*
X926486Y557086D01*
G01X888962Y843262D02*
X933596Y798628D01*
G01X891200Y838200D02*
X932447Y796953D01*
G01X879976Y936500D02*
X896397D01*
G01X873187Y943289D02*
X879976Y936500D01*
G01X893711Y978389D02*
X869800Y1002300D01*
G01X895837Y978389D02*
X893711D01*
G01X893554Y975434D02*
X868888Y1000100D01*
G01X898617Y975434D02*
X893554D01*
G01X890008Y960700D02*
X928293D01*
G01X869008Y981700D02*
X890008Y960700D01*
G01X885448Y949700D02*
X875848Y959300D01*
G01X931367Y949700D02*
X885448D01*
G01X889096Y958500D02*
X929205D01*
G01X871796Y975800D02*
X889096Y958500D01*
G01X882712Y943100D02*
X911676D01*
G01X875923Y949889D02*
X882712Y943100D01*
G01X888184Y956300D02*
X930117D01*
G01X870984Y973500D02*
X888184Y956300D01*
G01X886360Y951900D02*
X870629Y967631D01*
G01X931198Y951900D02*
X886360D01*
G01X891100Y963300D02*
X870500Y983900D01*
G01X904373Y963300D02*
X891100D01*
G01X880888Y938700D02*
X874099Y945489D01*
G01X897310Y938700D02*
X880888D01*
G01X893400Y965800D02*
X867680Y991520D01*
G01X902007Y965800D02*
X893400D01*
G01X883624Y945300D02*
X876835Y952089D01*
G01X938299Y945300D02*
X883624D01*
G01X884536Y947500D02*
X939257D01*
G01X875536Y956500D02*
X884536Y947500D01*
G01X881800Y940900D02*
X904100D01*
G01X875011Y947689D02*
X881800Y940900D01*
G01X894212Y968100D02*
X868592Y993720D01*
G01X900500Y968100D02*
X894212D01*
G01X887272Y954100D02*
X870472Y970900D01*
G01X931029Y954100D02*
X887272D01*
G01X894408Y971468D02*
X868177Y997699D01*
G01X899846Y971468D02*
X894408D01*
G01X894562Y1022062D02*
X892138Y1019638D01*
G01X893868Y1023737D02*
X892168Y1022037D01*
G01X914863Y1023737D02*
X893868D01*
G01X863590Y991520D02*
X861811Y993299D01*
G01X867680Y991520D02*
X863590D01*
G01X864502Y993720D02*
X862723Y995499D01*
G01X868592Y993720D02*
X864502D01*
G01X893054Y1025700D02*
X891354Y1024000D01*
G01X915300Y1025700D02*
X893054D01*
G01X864073Y1314673D02*
Y1314672D01*
G01X879725Y1330325D02*
X864073Y1314673D01*
G01X887763Y1341863D02*
X848398D01*
G01X897738Y1351838D02*
X887763Y1341863D01*
G01X1010426Y1330325D02*
X879725D01*
G01X893800Y1339100D02*
X849543D01*
G01X896500Y1341800D02*
X893800Y1339100D01*
G01X1012444Y1334000D02*
X877400D01*
G01X886520Y1344863D02*
X847155D01*
G01X896495Y1354838D02*
X886520Y1344863D01*
G01X1016600Y1332000D02*
X879031D01*
G01X893606Y1388600D02*
X894400D01*
G01X893593Y1388587D02*
X893606Y1388600D01*
G01X863187Y1388587D02*
X893593D01*
G01X894400Y1388600D02*
X895900Y1390100D01*
G01X892800Y1390500D02*
X896100Y1393800D01*
G01X861988Y1390500D02*
X892800D01*
G01X889518Y1395018D02*
X896100Y1401600D01*
G01X860282Y1395018D02*
X889518D01*
G01X891000Y1392700D02*
X896200Y1397900D01*
G01X861076Y1392700D02*
X891000D01*
G01X863900Y1386000D02*
X896200D01*
G01X888118Y1397218D02*
X896200Y1405300D01*
G01X859370Y1397218D02*
X888118D01*
G01X886792Y1404100D02*
X896889Y1414197D01*
G01X890200Y1508534D02*
X900239Y1498495D01*
G01X890200Y1545850D02*
Y1508534D01*
G01X888800Y1502827D02*
Y1493500D01*
G01X885175Y1506452D02*
X888800Y1502827D01*
G01X885175Y1569675D02*
Y1506452D01*
G01X888525Y1507840D02*
Y1546545D01*
G01X898564Y1497801D02*
X888525Y1507840D01*
G01X886850Y1507146D02*
Y1567350D01*
G01X896889Y1497107D02*
X886850Y1507146D01*
G01X893246Y1548896D02*
X890200Y1545850D01*
G01X893246Y1555148D02*
Y1548896D01*
G01X902500Y1564402D02*
X893246Y1555148D01*
G01X891571Y1555842D02*
X900300Y1564571D01*
G01X891571Y1549590D02*
Y1555842D01*
G01X889506Y1547525D02*
X891571Y1549590D01*
G01X889505Y1547525D02*
X889506D01*
G01X888525Y1546545D02*
X889505Y1547525D01*
G01X892805Y1577305D02*
X885175Y1569675D01*
G01X892805Y1597085D02*
Y1577305D01*
G01X893100Y1597380D02*
X892805Y1597085D01*
G01X893100Y1615980D02*
Y1597380D01*
G01X886850Y1567350D02*
X894730Y1575230D01*
G01X894520Y1617400D02*
X893100Y1615980D01*
G01X896775Y1640945D02*
X894520Y1638690D01*
G01X928232Y-8547D02*
X928138Y-8453D01*
G01X994659Y-8547D02*
X928232D01*
G01X922770Y176D02*
X997339D01*
G01X922687Y93D02*
X922770Y176D01*
G01X904809Y344189D02*
X920581Y359961D01*
G01X908007Y370178D02*
X894750Y356921D01*
G01X903245Y345864D02*
X920205Y362824D01*
G01X927792Y352818D02*
X963456D01*
G01X911072Y336098D02*
X927792Y352818D01*
G01X898622Y351555D02*
X913841Y366774D01*
G01X910480Y368503D02*
X895877Y353900D01*
G01X925900Y354493D02*
X964276D01*
G01X909850Y338443D02*
X925900Y354493D01*
G01X925045Y356557D02*
X965133D01*
G01X908606Y340118D02*
X925045Y356557D01*
G01X901845Y349498D02*
X917446Y365099D01*
G01X908105Y342231D02*
X924160Y358286D01*
G01X920581Y359961D02*
X968098D01*
G01X972110Y370178D02*
X908007D01*
G01X931516Y382858D02*
X1041500D01*
G01X906900Y407474D02*
X931516Y382858D01*
G01X920205Y362824D02*
X968394D01*
G01X913841Y366774D02*
X970312D01*
G01X899159Y373528D02*
X996243D01*
G01X899853Y371853D02*
X972804D01*
G01X970953Y368503D02*
X910480D01*
G01X917446Y365099D02*
X969322D01*
G01X924160Y358286D02*
X967403D01*
G01X909357Y450512D02*
Y456643D01*
G01X923800Y436069D02*
X909357Y450512D01*
G01X923800Y434804D02*
Y436069D01*
G01X923801Y434803D02*
X923800Y434804D01*
G01X923801Y431800D02*
Y434803D01*
G01X923800Y431799D02*
X923801Y431800D01*
G01X923800Y427959D02*
Y431799D01*
G01X929118Y422641D02*
X923800Y427959D01*
G01X930719Y422641D02*
X929118D01*
G01X934069Y419291D02*
X930719Y422641D01*
G01X954921Y419291D02*
X934069D01*
G01X906900Y425600D02*
Y407474D01*
G01X914407Y452604D02*
Y459693D01*
G01X927448Y439563D02*
X914407Y452604D01*
G01X934850Y439563D02*
X927448D01*
G01X939329Y444042D02*
X934850Y439563D01*
G01X945117Y444042D02*
X939329D01*
G01X926486Y557086D02*
X937205D01*
G01X935697Y800303D02*
X897000Y839000D01*
G01X1246737Y800303D02*
X935697D01*
G01X933596Y798628D02*
X1244942D01*
G01X938734Y802266D02*
X1247197D01*
G01X899000Y842000D02*
X938734Y802266D01*
G01X932447Y796953D02*
X1243647D01*
G01X914903Y888347D02*
X907034Y896216D01*
G01X1049126Y888347D02*
X914903D01*
G01X913862Y886147D02*
X904834Y895175D01*
G01X1048214Y886147D02*
X913862D01*
G01X912653Y883947D02*
X1047302D01*
G01X902571Y894029D02*
X912653Y883947D01*
G01X896465Y842000D02*
X899000D01*
G01X894965Y843500D02*
X896465Y842000D01*
G01X902359Y912970D02*
X898468D01*
G01X907034Y908295D02*
X902359Y912970D01*
G01X907034Y896216D02*
Y908295D01*
G01X902400Y909723D02*
X900615D01*
G01X904834Y907289D02*
X902400Y909723D01*
G01X904834Y895175D02*
Y907289D01*
G01X901756Y931141D02*
X904594D01*
G01X896397Y936500D02*
X901756Y931141D01*
G01X901729Y916712D02*
X896420D01*
G01X909234Y909207D02*
X901729Y916712D01*
G01X909234Y897298D02*
Y909207D01*
G01X915985Y890547D02*
X909234Y897298D01*
G01X1050038Y890547D02*
X915985D01*
G01X901442Y934568D02*
X897310Y938700D01*
G01X903368Y934568D02*
X901442D01*
G01X931085Y936172D02*
X949279Y917978D01*
G01X924053Y894947D02*
X1051862D01*
G01X917565Y901435D02*
X924053Y894947D01*
G01X917565Y924126D02*
Y901435D01*
G01X903979Y937712D02*
X917565Y924126D01*
G01X901540Y937712D02*
X903979D01*
G01X896679Y925500D02*
Y927505D01*
G01X911434Y910745D02*
X896679Y925500D01*
G01X911434Y898548D02*
Y910745D01*
G01X917235Y892747D02*
X911434Y898548D01*
G01X1050950Y892747D02*
X917235D01*
G01X902571Y906534D02*
Y894029D01*
G01X910258Y934742D02*
X917550D01*
G01X904100Y940900D02*
X910258Y934742D01*
G01X938445Y970852D02*
X951312D01*
G01X928293Y960700D02*
X938445Y970852D01*
G01X922407Y982874D02*
X909826D01*
G01X927381Y977900D02*
X922407Y982874D01*
G01X944900Y977900D02*
X927381D01*
G01X936789Y955122D02*
X931367Y949700D01*
G01X967702Y955122D02*
X936789D01*
G01X939357Y968652D02*
X950400D01*
G01X929205Y958500D02*
X939357Y968652D01*
G01X911676Y943100D02*
X916204Y938572D01*
G01X940268Y966451D02*
X969049D01*
G01X930117Y956300D02*
X940268Y966451D01*
G01X941874Y962576D02*
X931198Y951900D01*
G01X966204Y962576D02*
X941874D01*
G01X912994Y971921D02*
X904373Y963300D01*
G01X900184Y990500D02*
X895616Y985932D01*
G01X908107Y971900D02*
X902007Y965800D01*
G01X908107Y976899D02*
Y971900D01*
G01X910397Y979189D02*
X908107Y976899D01*
G01X951959Y931640D02*
X938299Y945300D01*
G01X939257Y947500D02*
X950572Y936185D01*
G01X905271Y972871D02*
X900500Y968100D01*
G01X905271Y974586D02*
Y972871D01*
G01X902621Y988277D02*
X896629Y982285D01*
G01X935157Y984736D02*
X931616Y988277D01*
G01X963428Y984736D02*
X935157D01*
G01X906838Y986077D02*
X902991Y982230D01*
G01X934245Y982536D02*
X930704Y986077D01*
G01X962516Y982536D02*
X934245D01*
G01X930704Y986077D02*
X906838D01*
G01X941180Y964251D02*
X931029Y954100D01*
G01X967841Y964251D02*
X941180D01*
G01X910040Y1006613D02*
X909953Y1006700D01*
G01X914138Y1022062D02*
X894562D01*
G01X917438Y1018762D02*
X914138Y1022062D01*
G01X962272Y1018762D02*
X917438D01*
G01X921751Y1008908D02*
X914659Y1016000D01*
G01X928532Y1008908D02*
X921751D01*
G01X933955Y1003485D02*
X928532Y1008908D01*
G01X939544Y1003485D02*
X933955D01*
G01X905445Y993038D02*
X961350D01*
G01X896371Y1002112D02*
X905445Y993038D01*
G01X923180Y998115D02*
X943708D01*
G01X920309Y995244D02*
X923180Y998115D01*
G01X911463Y995244D02*
X920309D01*
G01X903442Y1003265D02*
X911463Y995244D01*
G01X904144Y998556D02*
X904601D01*
G01X898200Y1004500D02*
X904144Y998556D01*
G01X921536Y1011900D02*
X1004040D01*
G01X915473Y1017963D02*
X921536Y1011900D01*
G01X960776Y990500D02*
X900184D01*
G01X918163Y1020437D02*
X914863Y1023737D01*
G01X962966Y1020437D02*
X918163D01*
G01X944674Y1028400D02*
X942689Y1030385D01*
G01X943762Y1026200D02*
X941862Y1028100D01*
G01X920839Y1006708D02*
X914108Y1013439D01*
G01X926095Y1006708D02*
X920839D01*
G01X932398Y1000405D02*
X926095Y1006708D01*
G01X946080Y1000405D02*
X932398D01*
G01X919656Y1003987D02*
X912504Y1011139D01*
G01X919656Y998764D02*
Y1003987D01*
G01X912900Y1007266D02*
X911227Y1008939D01*
G01X912900Y1003435D02*
Y1007266D01*
G01X911807Y1002342D02*
X912900Y1003435D01*
G01X917996Y1023004D02*
X915300Y1025700D01*
G01X963176Y1023004D02*
X917996D01*
G01X931616Y988277D02*
X902621D01*
G01X910387Y1055344D02*
X906331Y1059400D01*
G01X909677Y1038859D02*
X908060Y1037242D01*
G01X909677Y1038860D02*
Y1038859D01*
G01X911223Y1040406D02*
X909677Y1038860D01*
G01X962022Y1040406D02*
X911223D01*
G01X899152Y1056900D02*
X904875Y1051177D01*
G01X912912Y1038206D02*
X909748Y1035042D01*
G01X961110Y1038206D02*
X912912D01*
G01X921149Y1062424D02*
X916969Y1066604D01*
G01X914948Y1063255D02*
X913799Y1064404D01*
G01X920770Y1067389D02*
X919355Y1068804D01*
G01X966203Y1351838D02*
X897738D01*
G01X898000Y1343300D02*
X896500Y1341800D01*
G01X1011594Y1343300D02*
X898000D01*
G01X964578Y1354838D02*
X896495D01*
G01X900239Y1424330D02*
X945318Y1379251D01*
G01X917149Y1416756D02*
Y1490922D01*
G01X948054Y1385851D02*
X917149Y1416756D01*
G01X919349Y1417668D02*
X948966Y1388051D01*
G01X919349Y1491834D02*
Y1417668D01*
G01X945149Y1377051D02*
X898564Y1423636D01*
G01X896889Y1414197D02*
Y1497107D01*
G01X914949Y1415844D02*
Y1490010D01*
G01X947142Y1383651D02*
X914949Y1415844D01*
G01X912749Y1414932D02*
Y1489841D01*
G01X946230Y1381451D02*
X912749Y1414932D01*
G01X900239Y1498495D02*
Y1424330D01*
G01X898564Y1423636D02*
Y1497801D01*
G01X901867Y1506204D02*
Y1525591D01*
G01X917149Y1490922D02*
X901867Y1506204D01*
G01X904067Y1507116D02*
X919349Y1491834D01*
G01X904067Y1542857D02*
Y1507116D01*
G01X897547Y1507412D02*
Y1544638D01*
G01X914949Y1490010D02*
X897547Y1507412D01*
G01X895872Y1506718D02*
Y1543943D01*
G01X912749Y1489841D02*
X895872Y1506718D01*
G01X902500Y1581532D02*
Y1564402D01*
G01X909100Y1563152D02*
Y1574286D01*
G01X898271Y1552323D02*
X909100Y1563152D01*
G01X898271Y1546283D02*
Y1552323D01*
G01X901867Y1542687D02*
X898271Y1546283D01*
G01X901867Y1527409D02*
Y1542687D01*
G01X901963Y1527313D02*
X901867Y1527409D01*
G01X901963Y1525687D02*
Y1527313D01*
G01X901867Y1525591D02*
X901963Y1525687D01*
G01X904037Y1542887D02*
X904067Y1542857D01*
G01X904036Y1542887D02*
X904037D01*
G01X899946Y1546977D02*
X904036Y1542887D01*
G01X899946Y1550886D02*
Y1546977D01*
G01X911516Y1562456D02*
X899946Y1550886D01*
G01X911516Y1573202D02*
Y1562456D01*
G01X900300Y1564571D02*
Y1583216D01*
G01X906900Y1564064D02*
Y1577565D01*
G01X896596Y1553760D02*
X906900Y1564064D01*
G01X896596Y1545589D02*
Y1553760D01*
G01X897547Y1544638D02*
X896596Y1545589D01*
G01X904700Y1564233D02*
Y1579529D01*
G01X894921Y1554454D02*
X904700Y1564233D01*
G01X894921Y1544894D02*
Y1554454D01*
G01X895872Y1543943D02*
X894921Y1544894D01*
G01X897038Y1584594D02*
Y1577600D01*
G01X901700Y1589256D02*
X897038Y1584594D01*
G01X901700Y1623353D02*
Y1589256D01*
G01X907854Y1586886D02*
X902500Y1581532D01*
G01X907854Y1599234D02*
Y1586886D01*
G01X904725Y1602363D02*
X907854Y1599234D01*
G01X909100Y1574286D02*
X911616Y1576802D01*
G01X904725Y1587641D02*
Y1598032D01*
G01X900300Y1583216D02*
X904725Y1587641D01*
G01X895025Y1614335D02*
X897638Y1616948D01*
G01X895025Y1596582D02*
Y1614335D01*
G01X894730Y1596287D02*
X895025Y1596582D01*
G01X894730Y1575230D02*
Y1596287D01*
G01X906900Y1577565D02*
X911710Y1582375D01*
G01X904700Y1579529D02*
X911094Y1585923D01*
G01X904725Y1626378D02*
X901700Y1623353D01*
G01X894520Y1638690D02*
Y1617400D01*
G01X897638Y1640945D02*
X896775D01*
G01X897638Y1616948D02*
Y1618111D01*
G01X994450Y-70850D02*
X989050D01*
G01X979405Y50577D02*
X1029900Y82D01*
G01X979405Y348654D02*
Y50577D01*
G01X988602Y62966D02*
Y353686D01*
G01X1042368Y9200D02*
X988602Y62966D01*
G01X981902Y50985D02*
X1031130Y1757D01*
G01X981902Y349316D02*
Y50985D01*
G01X970493Y43057D02*
X1020238Y-6688D01*
G01X970493Y345781D02*
Y43057D01*
G01X985252Y55355D02*
X1035500Y5107D01*
G01X985252Y351834D02*
Y55355D01*
G01X986927Y58421D02*
Y352529D01*
G01X1037823Y7525D02*
X986927Y58421D01*
G01X972393Y45814D02*
X1023220Y-5013D01*
G01X972393Y346376D02*
Y45814D01*
G01X974627Y47333D02*
X1025298Y-3338D01*
G01X974627Y347063D02*
Y47333D01*
G01X983577Y52686D02*
X1032831Y3432D01*
G01X983577Y350844D02*
Y52686D01*
G01X977133Y48959D02*
X1027685Y-1593D01*
G01X977133Y348556D02*
Y48959D01*
G01X968098Y359961D02*
X979405Y348654D01*
G01X988602Y353686D02*
X972110Y370178D01*
G01X968394Y362824D02*
X981902Y349316D01*
G01X963456Y352818D02*
X970493Y345781D01*
G01X970312Y366774D02*
X985252Y351834D01*
G01X986927Y352529D02*
X970953Y368503D01*
G01X964276Y354493D02*
X972393Y346376D01*
G01X965133Y356557D02*
X974627Y347063D01*
G01X969322Y365099D02*
X983577Y350844D01*
G01X967403Y358286D02*
X977133Y348556D01*
G01X982108Y362549D02*
X985688D01*
G01X972804Y371853D02*
X982108Y362549D01*
G01X946246Y442913D02*
X945117Y444042D01*
G01X954921Y442913D02*
X946246D01*
G01X970975Y737600D02*
X999839Y766464D01*
G01X956900Y737600D02*
X970975D01*
G01X972118Y734500D02*
X1001082Y763464D01*
G01X955400Y734500D02*
X972118D01*
G01X953200Y736700D02*
X955400Y734500D01*
G01X986490Y931867D02*
X981679Y936678D01*
G01X1023059Y931867D02*
X986490D01*
G01X971769Y921676D02*
X1017135D01*
G01X968698Y924747D02*
X971769Y921676D01*
G01X968698Y928957D02*
Y924747D01*
G01X990082Y935217D02*
X1025263D01*
G01X983926Y941373D02*
X990082Y935217D01*
G01X966000Y937500D02*
X969873Y941373D01*
G01X949279Y917978D02*
X1015309D01*
G01X974259Y929468D02*
X976419Y931628D01*
G01X974259Y926214D02*
Y929468D01*
G01X975447Y925026D02*
X974259Y926214D01*
G01X1018523Y925026D02*
X975447D01*
G01X961100Y931640D02*
X951959D01*
G01X971075Y920001D02*
X1016441D01*
G01X966220Y924856D02*
X971075Y920001D01*
G01X966220Y932244D02*
Y924856D01*
G01X967583Y933607D02*
X966220Y932244D01*
G01X977596Y926755D02*
X976460Y927891D01*
G01X1019906Y926755D02*
X977596D01*
G01X950572Y936185D02*
X960503D01*
G01X971340Y931934D02*
X974484Y935078D01*
G01X971340Y925766D02*
Y931934D01*
G01X973755Y923351D02*
X971340Y925766D01*
G01X1017829Y923351D02*
X973755D01*
G01X989388Y933542D02*
X1024160D01*
G01X984084Y938846D02*
X989388Y933542D01*
G01X979020Y962080D02*
Y960000D01*
G01X970249Y970851D02*
X979020Y962080D01*
G01X951313Y970851D02*
X970249D01*
G01X951312Y970852D02*
X951313Y970851D01*
G01X945500Y978500D02*
X944900Y977900D01*
G01X966050Y978500D02*
X945500D01*
G01X993549Y951001D02*
X966050Y978500D01*
G01X968780Y956200D02*
X967702Y955122D01*
G01X976100Y959120D02*
X979020Y956200D01*
G01X976100Y961900D02*
Y959120D01*
G01X969349Y968651D02*
X976100Y961900D01*
G01X950401Y968651D02*
X969349D01*
G01X950400Y968652D02*
X950401Y968651D01*
G01X982571Y980951D02*
Y987529D01*
G01X991682Y971840D02*
X982571Y980951D01*
G01X973900Y961600D02*
Y960000D01*
G01X969049Y966451D02*
X973900Y961600D01*
G01X968780Y960000D02*
X966204Y962576D01*
G01X989858Y967440D02*
X1017960D01*
G01X969404Y987894D02*
X989858Y967440D01*
G01X980371Y980039D02*
X990770Y969640D01*
G01X980371Y986617D02*
Y980039D01*
G01X990770Y969640D02*
X1020960D01*
G01X965582Y985694D02*
X960776Y990500D01*
G01X996285Y957601D02*
X968192Y985694D01*
G01D02*
X965582D01*
G01X969873Y941373D02*
X983926D01*
G01X980595Y994500D02*
X997758Y977337D01*
G01X964670Y983494D02*
X963428Y984736D01*
G01X967280Y983494D02*
X964670D01*
G01X995373Y955401D02*
X967280Y983494D01*
G01X963758Y981294D02*
X962516Y982536D01*
G01X966368Y981294D02*
X963758D01*
G01X994461Y953201D02*
X966368Y981294D01*
G01X971600Y960492D02*
X967841Y964251D01*
G01X971600Y958500D02*
Y960492D01*
G01X973900Y956200D02*
X971600Y958500D01*
G01X976213Y938846D02*
X984084D01*
G01X988196Y1007600D02*
X991000Y1004796D01*
G01X960308Y1007600D02*
X988196D01*
G01X959000Y1006292D02*
X960308Y1007600D01*
G01X959000Y1004100D02*
Y1006292D01*
G01X956600Y1001700D02*
X959000Y1004100D01*
G01X991000Y1003100D02*
X1005763Y988337D01*
G01X991000Y1004796D02*
Y1003100D01*
G01X959396Y1009800D02*
X993000D01*
G01X956600Y1007004D02*
X959396Y1009800D01*
G01X956600Y1005700D02*
Y1007004D01*
G01X962273Y1018761D02*
X962272Y1018762D01*
G01X965287Y1018761D02*
X962273D01*
G01X965288Y1018762D02*
X965287Y1018761D01*
G01X979462Y1018762D02*
X965288D01*
G01X986606Y1025906D02*
X979462Y1018762D01*
G01X1036301Y1025906D02*
X986606D01*
G01X961220Y999392D02*
Y1001600D01*
G01X968312Y992300D02*
X961220Y999392D01*
G01X977800Y992300D02*
X968312D01*
G01X982571Y987529D02*
X977800Y992300D01*
G01X974020Y1028408D02*
X962022Y1040406D01*
G01X974020Y1026200D02*
Y1028408D01*
G01X966494Y987894D02*
X969404D01*
G01X961350Y993038D02*
X966494Y987894D01*
G01X976888Y990100D02*
X980371Y986617D01*
G01X967400Y990100D02*
X976888D01*
G01X962256Y995244D02*
X967400Y990100D01*
G01X946579Y995244D02*
X962256D01*
G01X943708Y998115D02*
X946579Y995244D01*
G01X971800Y1027516D02*
X961110Y1038206D01*
G01X971800Y1024620D02*
Y1027516D01*
G01X974020Y1022400D02*
X971800Y1024620D01*
G01X962967Y1020436D02*
X962966Y1020437D01*
G01X964593Y1020436D02*
X962967D01*
G01X964594Y1020437D02*
X964593Y1020436D01*
G01X975037Y1020437D02*
X964594D01*
G01X982181Y1027581D02*
X975037Y1020437D01*
G01X1036995Y1027581D02*
X982181D01*
G01X982831Y1001600D02*
X1000494Y983937D01*
G01X971460Y1001600D02*
X982831D01*
G01X964692Y1028400D02*
X944674D01*
G01X966700Y1026392D02*
X964692Y1028400D01*
G01X966700Y1024600D02*
Y1026392D01*
G01X968900Y1022400D02*
X966700Y1024600D01*
G01X963780Y1026200D02*
X943762D01*
G01X947759Y998726D02*
X946080Y1000405D01*
G01X969260Y1002480D02*
X966340Y1005400D01*
G01X969260Y1000688D02*
Y1002480D01*
G01X971048Y998900D02*
X969260Y1000688D01*
G01X982419Y998900D02*
X971048D01*
G01X999582Y981737D02*
X982419Y998900D01*
G01X969224Y994500D02*
X980595D01*
G01X964140Y999584D02*
X969224Y994500D01*
G01X964140Y1002480D02*
Y999584D01*
G01X961220Y1005400D02*
X964140Y1002480D01*
G01X981507Y996700D02*
X998670Y979537D01*
G01X970136Y996700D02*
X981507D01*
G01X967200Y999636D02*
X970136Y996700D01*
G01X967200Y1000740D02*
Y999636D01*
G01X966340Y1001600D02*
X967200Y1000740D01*
G01X983743Y1003800D02*
X1001406Y986137D01*
G01X973060Y1003800D02*
X983743D01*
G01X971460Y1005400D02*
X973060Y1003800D01*
G01X946919Y1035919D02*
X943600Y1032600D01*
G01X968900Y1027304D02*
X960285Y1035919D01*
G01X968900Y1026200D02*
Y1027304D01*
G01X963780Y1022400D02*
X963176Y1023004D01*
G01X960285Y1035919D02*
X946919D01*
G01X1010843Y1111200D02*
X977543Y1144500D01*
G01X1011671Y1091700D02*
X973244Y1130127D01*
G01X1013631Y1105300D02*
X977803Y1141128D01*
G01X1010895Y1098700D02*
X975068Y1134527D01*
G01X1011807Y1100900D02*
X975980Y1136727D01*
G01X1012719Y1103100D02*
X976892Y1138927D01*
G01X1009983Y1096500D02*
X974156Y1132327D01*
G01X983481Y1173419D02*
X995193Y1161707D01*
G01X966949Y1173419D02*
X983481D01*
G01X965941Y1174427D02*
X966949Y1173419D01*
G01X963000Y1174427D02*
X965941D01*
G01X960589Y1144500D02*
X955118Y1149971D01*
G01X977543Y1144500D02*
X960589D01*
G01X982569Y1171219D02*
X957871D01*
G01X994281Y1159507D02*
X982569Y1171219D01*
G01X963438Y1151100D02*
X957967Y1156571D01*
G01X980279Y1151100D02*
X963438D01*
G01X987272Y1144107D02*
X980279Y1151100D01*
G01X1023934Y1144107D02*
X987272D01*
G01X981158Y1165929D02*
X991980Y1155107D01*
G01X962941Y1165929D02*
X981158D01*
G01X981465Y1162510D02*
X991068Y1152907D01*
G01X966900Y1162510D02*
X981465D01*
G01X965793Y1163617D02*
X966900Y1162510D01*
G01X958870Y1163617D02*
X965793D01*
G01X991068Y1152907D02*
X1027834D01*
G01X981397Y1168802D02*
X992892Y1157307D01*
G01X967497Y1168802D02*
X981397D01*
G01X990156Y1150707D02*
X1026922D01*
G01X980553Y1160310D02*
X990156Y1150707D01*
G01X964537Y1160310D02*
X980553D01*
G01X965262Y1155500D02*
X959791Y1160971D01*
G01X982103Y1155500D02*
X965262D01*
G01X989096Y1148507D02*
X982103Y1155500D01*
G01X1025758Y1148507D02*
X989096D01*
G01X967763Y1175382D02*
X966755Y1176390D01*
G01X984295Y1175382D02*
X967763D01*
G01X994649Y1165028D02*
X984295Y1175382D01*
G01X964350Y1153300D02*
X958879Y1158771D01*
G01X981191Y1153300D02*
X964350D01*
G01X988184Y1146307D02*
X981191Y1153300D01*
G01X1024846Y1146307D02*
X988184D01*
G01X962413Y1148900D02*
X956942Y1154371D01*
G01X979367Y1148900D02*
X962413D01*
G01X1012667Y1115600D02*
X979367Y1148900D01*
G01X961501Y1146700D02*
X956030Y1152171D01*
G01X978455Y1146700D02*
X961501D01*
G01X1011755Y1113400D02*
X978455Y1146700D01*
G01X962900Y1255900D02*
X948900Y1241900D01*
G01X1071474Y1255900D02*
X962900D01*
G01X961200Y1264300D02*
X1073900D01*
G01X946038Y1249138D02*
X961200Y1264300D01*
G01X964100Y1253300D02*
X950500Y1239700D01*
G01X1051300Y1253300D02*
X964100D01*
G01X962662Y1262100D02*
X947500Y1246938D01*
G01X1070105Y1262100D02*
X962662D01*
G01X962374Y1258700D02*
X948412Y1244738D01*
G01X1046987Y1258700D02*
X962374D01*
G01X970902Y1356537D02*
X966203Y1351838D01*
G01X1027737Y1356537D02*
X970902D01*
G01X969277Y1359537D02*
X964578Y1354838D01*
G01X1026494Y1359537D02*
X969277D01*
G01X945318Y1379251D02*
X1020311D01*
G01X1017575Y1385851D02*
X948054D01*
G01X948966Y1388051D02*
X1016663D01*
G01X1021223Y1377051D02*
X945149D01*
G01X1018487Y1383651D02*
X947142D01*
G01X1019399Y1381451D02*
X946230D01*
G01X1004082Y-38200D02*
Y-17970D01*
G01X997800Y-67500D02*
X994450Y-70850D01*
G01X1022500Y-67500D02*
X997800D01*
G01X1025300Y-70300D02*
X1022500Y-67500D01*
G01X1067600Y-70300D02*
X1025300D01*
G01X1029900Y82D02*
X1126740D01*
G01X1004082Y-17970D02*
X994659Y-8547D01*
G01X1031130Y1757D02*
X1126046D01*
G01X1016578Y-19063D02*
X1127716D01*
G01X997339Y176D02*
X1016578Y-19063D01*
G01X1020238Y-6688D02*
X1126670D01*
G01X1035500Y5107D02*
X1124658D01*
G01X1124348Y7525D02*
X1037823D01*
G01X1023220Y-5013D02*
X1127364D01*
G01X1025298Y-3338D02*
X1128058D01*
G01X1032831Y3432D02*
X1125352D01*
G01X1027685Y-1593D02*
X1126046D01*
G01X1012583Y357188D02*
X1020250D01*
G01X996243Y373528D02*
X1012583Y357188D01*
G01X999839Y766464D02*
X1230615D01*
G01X1001082Y763464D02*
X1228772D01*
G01X1044347Y910579D02*
X1023059Y931867D01*
G01X1042347Y923836D02*
X1036431Y929752D01*
G01X1042221Y933300D02*
X1037083D01*
G01X1031840Y907900D02*
X1040393Y899347D01*
G01X1030911Y907900D02*
X1031840D01*
G01X1017135Y921676D02*
X1030911Y907900D01*
G01X1038416Y924349D02*
X1047765Y915000D01*
G01X1036131Y924349D02*
X1038416D01*
G01X1025263Y935217D02*
X1036131Y924349D01*
G01X1015309Y917978D02*
X1016842Y916445D01*
G01X1031249Y912300D02*
X1018523Y925026D01*
G01X1033664Y912300D02*
X1031249D01*
G01X1039785Y906179D02*
X1033664Y912300D01*
G01X1031146Y906225D02*
X1039699Y897672D01*
G01X1030217Y906225D02*
X1031146D01*
G01X1016441Y920001D02*
X1030217Y906225D01*
G01X1028912Y917749D02*
X1019906Y926755D01*
G01X1031543Y917749D02*
X1028912D01*
G01X1040913Y908379D02*
X1031543Y917749D01*
G01X1031080Y910100D02*
X1017829Y923351D01*
G01X1032752Y910100D02*
X1031080D01*
G01X1038873Y903979D02*
X1032752Y910100D01*
G01X1058536Y903979D02*
X1038873D01*
G01X1036979Y922674D02*
X1046874Y912779D01*
G01X1035028Y922674D02*
X1036979D01*
G01X1024160Y933542D02*
X1035028Y922674D01*
G01X1032062Y980637D02*
X1061093D01*
G01X1024362Y988337D02*
X1032062Y980637D01*
G01X1032974Y982837D02*
X1062005D01*
G01X1025274Y990537D02*
X1032974Y982837D01*
G01X1036858Y951001D02*
X993549D01*
G01X1061760Y926099D02*
X1036858Y951001D01*
G01X1021887Y971840D02*
X991682D01*
G01X1026607Y967120D02*
X1021887Y971840D01*
G01X1055938Y967120D02*
X1026607D01*
G01X1033886Y985037D02*
X1062917D01*
G01X1026186Y992737D02*
X1033886Y985037D01*
G01X1025600Y959800D02*
X1051815D01*
G01X1017960Y967440D02*
X1025600Y959800D01*
G01X1025680Y964920D02*
X1055026D01*
G01X1020960Y969640D02*
X1025680Y964920D01*
G01X1060848Y923899D02*
X1035947Y948800D01*
G01X1039594Y957601D02*
X996285D01*
G01X1064496Y932699D02*
X1039594Y957601D01*
G01X1030538Y975937D02*
X1059569D01*
G01X1022538Y983937D02*
X1030538Y975937D01*
G01X1000494Y983937D02*
X1022538D01*
G01X1021626Y981737D02*
X999582D01*
G01X1029626Y973737D02*
X1021626Y981737D01*
G01X1058657Y973737D02*
X1029626D01*
G01X1027519Y969320D02*
X1056850D01*
G01X1019502Y977337D02*
X1027519Y969320D01*
G01X997758Y977337D02*
X1019502D01*
G01X1028431Y971520D02*
X1057762D01*
G01X1020414Y979537D02*
X1028431Y971520D01*
G01X998670Y979537D02*
X1020414D01*
G01X1031450Y978137D02*
X1060481D01*
G01X1023450Y986137D02*
X1031450Y978137D01*
G01X1001406Y986137D02*
X1023450D01*
G01X1038682Y955401D02*
X995373D01*
G01X1063584Y930499D02*
X1038682Y955401D01*
G01X1037770Y953201D02*
X994461D01*
G01X1062672Y928299D02*
X1037770Y953201D01*
G01X1005763Y988337D02*
X1024362D01*
G01X1008481Y990537D02*
X1025274D01*
G01X1000700Y998318D02*
X1008481Y990537D01*
G01X1000700Y1002100D02*
Y998318D01*
G01X993000Y1009800D02*
X1000700Y1002100D01*
G01X1056907Y1005300D02*
X1036301Y1025906D01*
G01X1024850Y1005504D02*
X1023214Y1007140D01*
G01X1041410Y1005504D02*
X1024850D01*
G01X1009263Y992737D02*
X1026186D01*
G01X1005294Y996706D02*
X1009263Y992737D01*
G01X1005294Y997940D02*
Y996706D01*
G01X1040181Y1009103D02*
X1028657D01*
G01X1035898Y1023940D02*
X1020654D01*
G01X1056213Y1003625D02*
X1035898Y1023940D01*
G01X1012974Y1021215D02*
Y1021240D01*
G01X1016664Y1017525D02*
X1012974Y1021215D01*
G01X1034195Y1017525D02*
X1016664D01*
G01X1053120Y998600D02*
X1034195Y1017525D01*
G01X1015534Y1021024D02*
Y1023840D01*
G01X1017358Y1019200D02*
X1015534Y1021024D01*
G01X1035226Y1019200D02*
X1017358D01*
G01X1054151Y1000275D02*
X1035226Y1019200D01*
G01X1008300Y1007640D02*
X1013700D01*
G01X1004040Y1011900D02*
X1008300Y1007640D01*
G01X1057228Y1007348D02*
X1036995Y1027581D01*
G01X1011217Y997137D02*
X1010414Y997940D01*
G01X1028010Y997137D02*
X1011217D01*
G01X1035710Y989437D02*
X1028010Y997137D01*
G01X1064741Y989437D02*
X1035710D01*
G01X1012816Y999338D02*
X1010414Y1001740D01*
G01X1028921Y999338D02*
X1012816D01*
G01X1036622Y991637D02*
X1028921Y999338D01*
G01X1065653Y991637D02*
X1036622D01*
G01X1035892Y1021240D02*
X1018094D01*
G01X1055182Y1001950D02*
X1035892Y1021240D01*
G01X1034798Y987237D02*
X1063829D01*
G01X1027098Y994937D02*
X1034798Y987237D01*
G01X1010305Y994937D02*
X1027098D01*
G01X1007600Y997642D02*
X1010305Y994937D01*
G01X1007600Y999434D02*
Y997642D01*
G01X1005294Y1001740D02*
X1007600Y999434D01*
G01X1020471Y1003829D02*
X1040716D01*
G01X1014450Y1009850D02*
X1020471Y1003829D01*
G01X1009509Y1009850D02*
X1014450D01*
G01X1030636Y1111200D02*
X1010843D01*
G01X1034336Y1107500D02*
X1030636Y1111200D01*
G01X1062000Y1107500D02*
X1034336D01*
G01X1036160Y1091700D02*
X1011671D01*
G01X1039600Y1105300D02*
X1013631D01*
G01X1048960Y1095940D02*
X1039600Y1105300D01*
G01X1036072Y1098700D02*
X1010895D01*
G01X1038200Y1096572D02*
X1036072Y1098700D01*
G01X1038200Y1094780D02*
Y1096572D01*
G01X1041280Y1091700D02*
X1038200Y1094780D01*
G01X1033600Y1121580D02*
Y1134441D01*
G01X1041280Y1113900D02*
X1033600Y1121580D01*
G01X1037000Y1100900D02*
X1011807D01*
G01X1041280Y1096620D02*
X1037000Y1100900D01*
G01X1038680Y1103100D02*
X1012719D01*
G01X1041280Y1100500D02*
X1038680Y1103100D01*
G01X1035160Y1096500D02*
X1009983D01*
G01X1036160Y1095500D02*
X1035160Y1096500D01*
G01X1038800Y1120180D02*
Y1132353D01*
G01X1041280Y1117700D02*
X1038800Y1120180D01*
G01X1032460Y1115600D02*
X1012667D01*
G01X1036160Y1111900D02*
X1032460Y1115600D01*
G01X1031548Y1113400D02*
X1011755D01*
G01X1035248Y1109700D02*
X1031548Y1113400D01*
G01X1062800Y1109700D02*
X1035248D01*
G01X1031567Y1161707D02*
X1049259Y1144015D01*
G01X995193Y1161707D02*
X1031567D01*
G01X1030655Y1159507D02*
X994281D01*
G01X1051145Y1139017D02*
X1030655Y1159507D01*
G01X1033600Y1134441D02*
X1023934Y1144107D01*
G01X1028746Y1155107D02*
X1049236Y1134617D01*
G01X991980Y1155107D02*
X1028746D01*
G01X1027834Y1152907D02*
X1048324Y1132417D01*
G01X1029658Y1157307D02*
X1050148Y1136817D01*
G01X992892Y1157307D02*
X1029658D01*
G01X1026922Y1150707D02*
X1047412Y1130217D01*
G01X1041280Y1132985D02*
X1025758Y1148507D01*
G01X1021300Y1188800D02*
X1045000Y1165100D01*
G01X1023124Y1193200D02*
X1044724Y1171600D01*
G01X1032456Y1165028D02*
X994649D01*
G01X1045192Y1152292D02*
X1032456Y1165028D01*
G01X1020388Y1186600D02*
X1044681Y1162307D01*
G01X1022212Y1191000D02*
X1045212Y1168000D01*
G01X1038800Y1132353D02*
X1024846Y1146307D01*
G01X1029312Y1203900D02*
X1056712Y1176500D01*
G01X1034100Y1212700D02*
X1060000Y1186800D01*
G01X1036588Y1214900D02*
X1060344Y1191144D01*
G01X1037500Y1217100D02*
X1048100Y1206500D01*
G01X1032800Y1210500D02*
X1059200Y1184100D01*
G01X995800Y1188800D02*
X1021300D01*
G01X992673Y1191927D02*
X995800Y1188800D01*
G01X1012439Y1193200D02*
X1023124D01*
G01X1008139Y1197500D02*
X1012439Y1193200D01*
G01X1030976Y1206100D02*
X1057986Y1179090D01*
G01X1053743Y1174221D02*
X1026264Y1201700D01*
G01X994888Y1186600D02*
X1020388D01*
G01X991998Y1189490D02*
X994888Y1186600D01*
G01X1011527Y1191000D02*
X1022212D01*
G01X1007227Y1195300D02*
X1011527Y1191000D01*
G01X1031888Y1208300D02*
X1058288Y1181900D01*
G01X1016835Y1323916D02*
X1010426Y1330325D01*
G01X1030434Y1359234D02*
X1027737Y1356537D01*
G01X1067266Y1359234D02*
X1030434D01*
G01X1012994Y1344700D02*
X1011594Y1343300D01*
G01X1081037Y1344700D02*
X1012994D01*
G01X1016672Y1338228D02*
X1012444Y1334000D01*
G01X1029191Y1362234D02*
X1026494Y1359537D01*
G01X1111553Y1362234D02*
X1029191D01*
G01X1020311Y1379251D02*
X1061176Y1420116D01*
G01X1058440Y1426716D02*
X1017575Y1385851D01*
G01X1016663Y1388051D02*
X1057528Y1428916D01*
G01X1062088Y1417916D02*
X1021223Y1377051D01*
G01X1059352Y1424516D02*
X1018487Y1383651D01*
G01X1060264Y1422316D02*
X1019399Y1381451D01*
G01X1083376Y-41306D02*
X1078900Y-45782D01*
G01X1118555Y-41306D02*
X1083376D01*
G01X1070918Y-73618D02*
X1067600Y-70300D01*
G01X1087311Y12599D02*
X1077505Y22405D01*
G01X1105315Y12599D02*
X1087311D01*
G01X1123300Y9200D02*
X1042368D01*
G01X1044108Y-21101D02*
X1128047D01*
G01X1043513Y-21696D02*
X1044108Y-21101D01*
G01X1083105Y46195D02*
X1076905D01*
G01X1085792Y43508D02*
X1083105Y46195D01*
G01X1098828Y43508D02*
X1085792D01*
G01X1079369Y32757D02*
X1076944Y35182D01*
G01X1081112Y32757D02*
X1079369D01*
G01X1081585Y32284D02*
X1081112Y32757D01*
G01X1097441Y32284D02*
X1081585D01*
G01X1083088Y42612D02*
X1077260D01*
G01X1088454Y37246D02*
X1083088Y42612D01*
G01X1100118Y27282D02*
X1076299D01*
G01X1100546Y52000D02*
X1077400D01*
G01X1084349Y38982D02*
X1077082D01*
G01X1087760Y35571D02*
X1084349Y38982D01*
G01X1100061Y35571D02*
X1087760D01*
G01X1080418Y31082D02*
X1076418D01*
G01X1082418Y29082D02*
X1080418Y31082D01*
G01X1104580Y29082D02*
X1082418D01*
G01X1112134Y859717D02*
X1061272Y910579D01*
G01X1097556Y839917D02*
X1049126Y888347D01*
G01X1096644Y837717D02*
X1048214Y886147D01*
G01X1053686Y899347D02*
X1102116Y850917D01*
G01X1098468Y842117D02*
X1050038Y890547D01*
G01X1051862Y894947D02*
X1100292Y846517D01*
G01X1110310Y855317D02*
X1059448Y906179D01*
G01X1052249Y897672D02*
X1101204Y848717D01*
G01X1111222Y857517D02*
X1060360Y908379D01*
G01X1109398Y853117D02*
X1058536Y903979D01*
G01X1099380Y844317D02*
X1050950Y892747D01*
G01X1047302Y883947D02*
X1095732Y835517D01*
G01X1062184Y912779D02*
X1113046Y861917D01*
G01X1061272Y910579D02*
X1044347D01*
G01X1045461Y923836D02*
X1042347D01*
G01X1051998Y917299D02*
X1045461Y923836D01*
G01X1064120Y917299D02*
X1051998D01*
G01X1098016Y883403D02*
X1064120Y917299D01*
G01X1044970Y927130D02*
X1044101D01*
G01X1052601Y919499D02*
X1044970Y927130D01*
G01X1065032Y919499D02*
X1052601D01*
G01X1098928Y885603D02*
X1065032Y919499D01*
G01X1067768Y926099D02*
X1061760D01*
G01X1075965Y917902D02*
X1067768Y926099D01*
G01X1117122Y917902D02*
X1075965D01*
G01X1091305Y931753D02*
X1055938Y967120D01*
G01X1053822Y921699D02*
X1042221Y933300D01*
G01X1065944Y921699D02*
X1053822D01*
G01X1074438Y913205D02*
X1065944Y921699D01*
G01X1114439Y913205D02*
X1074438D01*
G01X1040393Y899347D02*
X1053686D01*
G01X1084262Y927353D02*
X1120799D01*
G01X1051815Y959800D02*
X1084262Y927353D01*
G01X1055026Y964920D02*
X1090393Y929553D01*
G01X1066856Y923899D02*
X1060848D01*
G01X1075350Y915405D02*
X1066856Y923899D01*
G01X1115351Y915405D02*
X1075350D01*
G01X1070504Y932699D02*
X1064496D01*
G01X1078050Y925153D02*
X1070504Y932699D01*
G01X1119887Y925153D02*
X1078050D01*
G01X1063075Y915000D02*
X1096872Y881203D01*
G01X1047765Y915000D02*
X1063075D01*
G01X1059448Y906179D02*
X1039785D01*
G01X1039699Y897672D02*
X1052249D01*
G01X1060360Y908379D02*
X1040913D01*
G01X1069592Y930499D02*
X1063584D01*
G01X1077138Y922953D02*
X1069592Y930499D01*
G01X1118339Y922953D02*
X1077138D01*
G01X1068680Y928299D02*
X1062672D01*
G01X1076226Y920753D02*
X1068680Y928299D01*
G01X1117427Y920753D02*
X1076226D01*
G01X1046874Y912779D02*
X1062184D01*
G01X1082722Y959008D02*
X1114140D01*
G01X1061093Y980637D02*
X1082722Y959008D01*
G01X1083634Y961208D02*
X1115052D01*
G01X1062005Y982837D02*
X1083634Y961208D01*
G01X1088405Y974604D02*
X1067759Y995250D01*
G01X1084546Y963408D02*
X1115964D01*
G01X1062917Y985037D02*
X1084546Y963408D01*
G01X1088974Y976404D02*
X1068453Y996925D01*
G01X1089668Y978079D02*
X1069147Y998600D01*
G01X1090362Y979754D02*
X1069841Y1000275D01*
G01X1059569Y975937D02*
X1094953Y940553D01*
G01X1086370Y967808D02*
X1064741Y989437D01*
G01X1117788Y967808D02*
X1086370D01*
G01X1087282Y970008D02*
X1065653Y991637D01*
G01X1118700Y970008D02*
X1087282D01*
G01X1094041Y938353D02*
X1058657Y973737D01*
G01X1056850Y969320D02*
X1092217Y933953D01*
G01X1057762Y971520D02*
X1093129Y936153D01*
G01X1081810Y956808D02*
X1113228D01*
G01X1060481Y978137D02*
X1081810Y956808D01*
G01X1091056Y981429D02*
X1070535Y1001950D01*
G01X1085458Y965608D02*
X1116876D01*
G01X1063829Y987237D02*
X1085458Y965608D01*
G01X1067065Y993575D02*
X1087711Y972929D01*
G01D02*
X1119079D01*
G01X1107058Y1005300D02*
X1056907D01*
G01X1051664Y995250D02*
X1041410Y1005504D01*
G01X1067759Y995250D02*
X1051664D01*
G01X1052359Y996925D02*
X1040181Y1009103D01*
G01X1068453Y996925D02*
X1052359D01*
G01X1072330Y1003625D02*
X1056213D01*
G01X1092851Y983104D02*
X1072330Y1003625D01*
G01X1069147Y998600D02*
X1053120D01*
G01X1069841Y1000275D02*
X1054151D01*
G01X1110522Y1007348D02*
X1057228D01*
G01X1070535Y1001950D02*
X1055182D01*
G01X1050970Y993575D02*
X1067065D01*
G01X1040716Y1003829D02*
X1050970Y993575D01*
G01X1076800Y1092700D02*
X1062000Y1107500D01*
G01X1083660Y1092700D02*
X1076800D01*
G01X1048960Y1095500D02*
Y1095940D01*
G01X1086997Y1095926D02*
X1100446D01*
G01X1065223Y1117700D02*
X1086997Y1095926D01*
G01X1054080Y1117700D02*
X1065223D01*
G01X1041280Y1095500D02*
Y1096620D01*
G01X1047412Y1130217D02*
X1092645D01*
G01X1048960Y1118860D02*
Y1117700D01*
G01X1052200Y1122100D02*
X1048960Y1118860D01*
G01X1074400Y1122100D02*
X1052200D01*
G01X1096000Y1100500D02*
X1074400Y1122100D01*
G01X1041280Y1121500D02*
Y1132985D01*
G01X1058451Y1089809D02*
X1095513D01*
G01X1048960Y1099300D02*
X1058451Y1089809D01*
G01X1053051Y1087609D02*
X1094601D01*
G01X1048960Y1091700D02*
X1053051Y1087609D01*
G01X1066607Y1113900D02*
X1088498Y1092009D01*
G01X1054080Y1113900D02*
X1066607D01*
G01X1077138Y1095362D02*
X1062800Y1109700D01*
G01X1081078Y1095362D02*
X1077138D01*
G01X1072600Y1119900D02*
X1094374Y1098126D01*
G01X1053100Y1119900D02*
X1072600D01*
G01X1051880Y1118680D02*
X1053100Y1119900D01*
G01X1051880Y1117680D02*
Y1118680D01*
G01X1048960Y1114760D02*
X1051880Y1117680D01*
G01X1048960Y1113900D02*
Y1114760D01*
G01X1052057Y1141217D02*
X1094976D01*
G01X1051384Y1141890D02*
X1052057Y1141217D01*
G01X1051169Y1141890D02*
X1051384D01*
G01X1049259Y1143800D02*
X1051169Y1141890D01*
G01X1049259Y1144015D02*
Y1143800D01*
G01X1081000Y1176500D02*
X1089600Y1185100D01*
G01X1056712Y1176500D02*
X1081000D01*
G01X1094807Y1139017D02*
X1051145D01*
G01X1049236Y1134617D02*
X1094469D01*
G01X1048324Y1132417D02*
X1093557D01*
G01X1050148Y1136817D02*
X1094638D01*
G01X1084200Y1165100D02*
X1089743Y1170643D01*
G01X1045000Y1165100D02*
X1084200D01*
G01X1087200Y1177900D02*
X1106123D01*
G01X1080900Y1171600D02*
X1087200Y1177900D01*
G01X1044724Y1171600D02*
X1080900D01*
G01X1057986Y1179090D02*
X1075600D01*
G01X1123070Y1152292D02*
X1045192D01*
G01X1086707Y1162307D02*
X1088100Y1163700D01*
G01X1044681Y1162307D02*
X1086707D01*
G01X1045212Y1168000D02*
X1046900D01*
G01X1086164Y1198164D02*
X1116568D01*
G01X1074800Y1186800D02*
X1086164Y1198164D01*
G01X1060000Y1186800D02*
X1074800D01*
G01X1060344Y1191144D02*
X1076032D01*
G01X1048100Y1206500D02*
X1111381D01*
G01X1059200Y1184100D02*
X1070000D01*
G01X1083746Y1191046D02*
X1112662D01*
G01X1074600Y1181900D02*
X1083746Y1191046D01*
G01X1058288Y1181900D02*
X1074600D01*
G01X1092774Y1234600D02*
X1071474Y1255900D01*
G01X1083105Y1273900D02*
X1093605Y1284400D01*
G01X1073900Y1264300D02*
X1089200Y1249000D01*
G01X1090605Y1241600D02*
X1070105Y1262100D01*
G01X1087800Y1270200D02*
X1084400Y1266800D01*
G01X1106151Y1270200D02*
X1087800D01*
G01X1089700Y1277100D02*
X1081800Y1269200D01*
G01X1047000Y1258687D02*
X1046987Y1258700D01*
G01X1071480Y1355020D02*
X1067266Y1359234D01*
G01X1105931Y1355020D02*
X1071480D01*
G01X1084987Y1340750D02*
X1081037Y1344700D01*
G01X1110202Y1340750D02*
X1084987D01*
G01X1061176Y1420116D02*
X1132549D01*
G01X1131354Y1417916D02*
X1062088D01*
G01X1136251Y1426716D02*
X1058440D01*
G01X1057528Y1428916D02*
X1137163D01*
G01X1134939Y1424516D02*
X1059352D01*
G01X1133744Y1422316D02*
X1060264D01*
G01X1170835Y10974D02*
X1118555Y-41306D01*
G01X1126740Y82D02*
X1161134Y34476D01*
G01X1157026Y42926D02*
X1123300Y9200D01*
G01X1126046Y1757D02*
X1160440Y36151D01*
G01X1127716Y-19063D02*
X1167029Y20250D01*
G01X1128047Y-21101D02*
X1167723Y18575D01*
G01X1129445Y-6689D02*
X1163910Y27776D01*
G01X1126671Y-6689D02*
X1129445D01*
G01X1126670Y-6688D02*
X1126671Y-6689D01*
G01X1124658Y5107D02*
X1159127Y39576D01*
G01X1158074Y41251D02*
X1124348Y7525D01*
G01X1128751Y-5014D02*
X1163216Y29451D01*
G01X1127365Y-5014D02*
X1128751D01*
G01X1127364Y-5013D02*
X1127365Y-5014D01*
G01X1128058Y-3338D02*
X1162522Y31126D01*
G01X1125352Y3432D02*
X1159746Y37826D01*
G01X1127433Y-1594D02*
X1161828Y32801D01*
G01X1126047Y-1594D02*
X1127433D01*
G01X1126046Y-1593D02*
X1126047Y-1594D01*
G01X1102765Y39571D02*
X1098828Y43508D01*
G01X1111807Y39571D02*
X1102765D01*
G01X1115157Y36221D02*
X1111807Y39571D01*
G01X1104290Y37246D02*
X1088454D01*
G01X1105315Y36221D02*
X1104290Y37246D01*
G01X1102300Y25100D02*
X1100118Y27282D01*
G01X1111600Y25100D02*
X1102300D01*
G01X1114847Y28347D02*
X1111600Y25100D01*
G01X1115157Y28347D02*
X1114847D01*
G01X1104046Y48500D02*
X1100546Y52000D01*
G01X1110752Y48500D02*
X1104046D01*
G01X1115157Y44095D02*
X1110752Y48500D01*
G01X1103348Y32284D02*
X1100061Y35571D01*
G01X1123031Y32284D02*
X1103348D01*
G01X1105315Y28347D02*
X1104580Y29082D01*
G01X1225684Y167600D02*
X1136203D01*
G01X1133700Y176500D02*
X1134110D01*
G01X1133700Y176725D02*
Y176500D01*
G01X1227702Y176725D02*
X1133700D01*
G01X1128825Y419291D02*
X1123031D01*
G01X1130859Y421325D02*
X1128825Y419291D01*
G01X1367775Y421325D02*
X1130859D01*
G01X1249865Y839917D02*
X1097556D01*
G01X1250777Y837717D02*
X1096644D01*
G01X1095732Y835517D02*
X1251689D01*
G01X1241257Y859717D02*
X1112134D01*
G01X1137775Y883403D02*
X1098016D01*
G01X1138687Y885603D02*
X1098928D01*
G01X1102116Y850917D02*
X1244905D01*
G01X1248953Y842117D02*
X1098468D01*
G01X1096872Y881203D02*
X1136622D01*
G01X1100292Y846517D02*
X1247129D01*
G01X1243081Y855317D02*
X1110310D01*
G01X1101204Y848717D02*
X1245817D01*
G01X1242169Y857517D02*
X1111222D01*
G01X1243993Y853117D02*
X1109398D01*
G01X1248041Y844317D02*
X1099380D01*
G01X1113046Y861917D02*
X1235937D01*
G01X1114140Y959008D02*
X1162331Y910817D01*
G01X1152879Y882145D02*
X1117122Y917902D01*
G01X1122623Y931753D02*
X1091305D01*
G01X1156759Y897617D02*
X1122623Y931753D01*
G01X1149899Y877745D02*
X1114439Y913205D01*
G01X1120799Y927353D02*
X1154935Y893217D01*
G01X1121711Y929553D02*
X1155847Y895417D01*
G01X1090393Y929553D02*
X1121711D01*
G01X1150811Y879945D02*
X1115351Y915405D01*
G01X1154023Y891017D02*
X1119887Y925153D01*
G01X1126371Y940553D02*
X1160507Y906417D01*
G01X1159595Y904217D02*
X1125459Y938353D01*
G01X1123535Y933953D02*
X1157671Y899817D01*
G01X1092217Y933953D02*
X1123535D01*
G01X1124547Y936153D02*
X1158683Y902017D01*
G01X1093129Y936153D02*
X1124547D01*
G01X1113228Y956808D02*
X1161419Y908617D01*
G01X1154639Y886653D02*
X1118339Y922953D01*
G01X1153835Y884345D02*
X1117427Y920753D01*
G01X1115052Y961208D02*
X1163243Y913017D01*
G01X1120004Y974604D02*
X1088405D01*
G01X1169153Y925455D02*
X1120004Y974604D01*
G01X1115964Y963408D02*
X1164155Y915217D01*
G01X1120573Y976404D02*
X1088974D01*
G01X1169847Y927130D02*
X1120573Y976404D01*
G01X1133576Y983104D02*
X1092851D01*
G01X1169871Y1019399D02*
X1133576Y983104D01*
G01X1136280Y978079D02*
X1089668D01*
G01X1172575Y1014374D02*
X1136280Y978079D01*
G01X1135586Y979754D02*
X1090362D01*
G01X1171881Y1016049D02*
X1135586Y979754D01*
G01X1094953Y940553D02*
X1126371D01*
G01X1165979Y919617D02*
X1117788Y967808D01*
G01X1166891Y921817D02*
X1118700Y970008D01*
G01X1125459Y938353D02*
X1094041D01*
G01X1134892Y981429D02*
X1091056D01*
G01X1171187Y1017724D02*
X1134892Y981429D01*
G01X1116876Y965608D02*
X1165067Y917417D01*
G01X1119079Y972929D02*
X1168228Y923780D01*
G01X1109593Y1002765D02*
X1107058Y1005300D01*
G01X1115105Y1002765D02*
X1110522Y1007348D01*
G01X1115372Y1081000D02*
X1214271D01*
G01X1100446Y1095926D02*
X1115372Y1081000D01*
G01X1109211Y1056289D02*
X1213164D01*
G01X1091494Y1074006D02*
X1109211Y1056289D01*
G01X1091494Y1075994D02*
Y1074006D01*
G01X1114311Y1065089D02*
X1216812D01*
G01X1103800Y1075600D02*
X1114311Y1065089D01*
G01X1111511Y1062889D02*
X1103800Y1070600D01*
G01X1215900Y1062889D02*
X1111511D01*
G01X1112273Y1073049D02*
X1215998D01*
G01X1095513Y1089809D02*
X1112273Y1073049D01*
G01X1111361Y1070849D02*
X1214609D01*
G01X1094601Y1087609D02*
X1111361Y1070849D01*
G01X1110311Y1060689D02*
X1214988D01*
G01X1100500Y1070500D02*
X1110311Y1060689D01*
G01X1100500Y1072100D02*
Y1070500D01*
G01X1097500Y1075100D02*
X1100500Y1072100D01*
G01X1110011Y1058489D02*
X1214076D01*
G01X1097800Y1070700D02*
X1110011Y1058489D01*
G01X1108211Y1054089D02*
X1091400Y1070900D01*
G01X1211611Y1054089D02*
X1108211D01*
G01X1113185Y1075249D02*
X1216910D01*
G01X1096425Y1092009D02*
X1113185Y1075249D01*
G01X1122688Y1113505D02*
X1210388D01*
G01X1094976Y1141217D02*
X1122688Y1113505D01*
G01X1122519Y1111305D02*
X1094807Y1139017D01*
G01X1209476Y1111305D02*
X1122519D01*
G01X1122181Y1106905D02*
X1207651D01*
G01X1094469Y1134617D02*
X1122181Y1106905D01*
G01X1121269Y1104705D02*
X1206267D01*
G01X1093557Y1132417D02*
X1121269Y1104705D01*
G01X1122350Y1109105D02*
X1208564D01*
G01X1094638Y1136817D02*
X1122350Y1109105D01*
G01X1120357Y1102505D02*
X1203995D01*
G01X1092645Y1130217D02*
X1120357Y1102505D01*
G01X1105500Y1100500D02*
X1096000D01*
G01X1120600Y1085400D02*
X1105500Y1100500D01*
G01X1217085Y1085400D02*
X1120600D01*
G01X1088498Y1092009D02*
X1096425D01*
G01X1116284Y1083200D02*
X1216173D01*
G01X1101358Y1098126D02*
X1116284Y1083200D01*
G01X1094374Y1098126D02*
X1101358D01*
G01X1115742Y1170643D02*
X1119042Y1167343D01*
G01X1089743Y1170643D02*
X1115742D01*
G01X1106123Y1177900D02*
X1109593Y1174430D01*
G01X1138183Y1137179D02*
X1123070Y1152292D01*
G01X1109887Y1163700D02*
X1113530Y1167343D01*
G01X1088100Y1163700D02*
X1109887D01*
G01X1115458Y1185100D02*
X1119042Y1181516D01*
G01X1089600Y1185100D02*
X1115458D01*
G01X1118375Y1206225D02*
X1268907D01*
G01X1114737Y1209863D02*
X1118375Y1206225D01*
G01X1113530Y1209863D02*
X1114737D01*
G01X1116568Y1198164D02*
X1119042Y1195690D01*
G01X1111381Y1206500D02*
X1115105Y1202776D01*
G01X1119042Y1224036D02*
X1122610Y1227604D01*
G01D02*
X1205303D01*
G01X1118656Y1220500D02*
X1273788D01*
G01X1115105Y1216949D02*
X1118656Y1220500D01*
G01X1122579Y1213400D02*
X1272970D01*
G01X1119042Y1209863D02*
X1122579Y1213400D01*
G01X1115105Y1231123D02*
X1111682Y1227700D01*
G01X1112662Y1191046D02*
X1115105Y1188603D01*
G01X1115433Y1234600D02*
X1092774D01*
G01X1119042Y1238209D02*
X1115433Y1234600D01*
G01X1122324Y1249100D02*
X1119042Y1252382D01*
G01X1255700Y1249100D02*
X1122324D01*
G01X1117148Y1256000D02*
X1257812D01*
G01X1113530Y1252382D02*
X1117148Y1256000D01*
G01X1105889Y1249000D02*
X1109593Y1245296D01*
G01X1089200Y1249000D02*
X1105889D01*
G01X1118636Y1263000D02*
X1115105Y1259469D01*
G01X1258188Y1263000D02*
X1118636D01*
G01X1119042Y1267842D02*
Y1266556D01*
G01X1121500Y1270300D02*
X1119042Y1267842D01*
G01X1254100Y1270300D02*
X1121500D01*
G01X1111409Y1241600D02*
X1090605D01*
G01X1115105Y1245296D02*
X1111409Y1241600D01*
G01X1109593Y1273642D02*
X1106151Y1270200D01*
G01X1115105Y1273642D02*
X1111647Y1277100D01*
G01X1115105Y1287816D02*
X1111421Y1291500D01*
G01X1115371Y1284400D02*
X1119042Y1280729D01*
G01X1093605Y1284400D02*
X1115371D01*
G01X1111647Y1277100D02*
X1089700D01*
G01X1109593Y1358682D02*
X1105931Y1355020D01*
G01X1113530Y1337422D02*
X1110202Y1340750D01*
G01X1115105Y1358682D02*
X1111553Y1362234D01*
G01X1132549Y1420116D02*
X1146401Y1406264D01*
G01X1121657Y1391500D02*
X1119042Y1394115D01*
G01X1137500Y1391500D02*
X1121657D01*
G01X1144088Y1405182D02*
X1131354Y1417916D01*
G01X1114385Y1394115D02*
X1113530D01*
G01X1119000Y1389500D02*
X1114385Y1394115D01*
G01X1136000Y1389500D02*
X1119000D01*
G01X1140000Y1385500D02*
X1136000Y1389500D01*
G01X1148601Y1407459D02*
X1133744Y1422316D01*
G01X1153001Y1409966D02*
X1136251Y1426716D01*
G01X1150801Y1408654D02*
X1134939Y1424516D01*
G01X1167723Y18575D02*
X1215012D01*
G01X1218124Y10974D02*
X1170835D01*
G01X1161134Y34476D02*
X1208423D01*
G01X1205028Y42926D02*
X1157026D01*
G01X1160440Y36151D02*
X1207729D01*
G01X1167029Y20250D02*
X1214318D01*
G01X1163910Y27776D02*
X1211199D01*
G01X1159127Y39576D02*
X1206416D01*
G01X1205722Y41251D02*
X1158074D01*
G01X1163216Y29451D02*
X1210505D01*
G01X1162522Y31126D02*
X1209811D01*
G01X1159746Y37826D02*
X1207035D01*
G01X1161828Y32801D02*
X1209117D01*
G01X1227983Y174637D02*
X1142800D01*
G01X1227115Y171400D02*
X1140500D01*
G01X1191835Y179200D02*
X1140550D01*
G01X1181588Y279212D02*
X1189996D01*
G01X1176300Y284500D02*
X1181588Y279212D01*
G01X1147833Y873345D02*
X1137775Y883403D01*
G01X1241141Y873345D02*
X1147833D01*
G01X1148745Y875545D02*
X1138687Y885603D01*
G01X1240229Y875545D02*
X1148745D01*
G01X1237417Y882145D02*
X1152879D01*
G01X1239241Y877745D02*
X1149899D01*
G01X1238329Y879945D02*
X1150811D01*
G01X1153708Y864117D02*
X1235025D01*
G01X1136622Y881203D02*
X1153708Y864117D01*
G01X1235401Y886653D02*
X1154639D01*
G01X1236205Y884345D02*
X1153835D01*
G01X1162331Y910817D02*
X1220317D01*
G01X1163243Y913017D02*
X1212117D01*
G01X1198424Y925455D02*
X1169153D01*
G01X1226790Y897617D02*
X1156759D01*
G01X1164155Y915217D02*
X1211205D01*
G01X1193830Y927130D02*
X1169847D01*
G01X1154935Y893217D02*
X1235741D01*
G01X1155847Y895417D02*
X1227965D01*
G01X1236653Y891017D02*
X1154023D01*
G01X1160507Y906417D02*
X1223142D01*
G01X1209381Y919617D02*
X1165979D01*
G01X1199932Y921817D02*
X1166891D01*
G01X1224054Y904217D02*
X1159595D01*
G01X1157671Y899817D02*
X1225878D01*
G01X1158683Y902017D02*
X1224966D01*
G01X1161419Y908617D02*
X1222230D01*
G01X1165067Y917417D02*
X1210293D01*
G01X1168228Y923780D02*
X1199118D01*
G01X1203000Y1019399D02*
X1169871D01*
G01X1199907Y1014374D02*
X1172575D01*
G01X1200938Y1016049D02*
X1171881D01*
G01X1201969Y1017724D02*
X1171187D01*
G01X1272641Y1137179D02*
X1138183D01*
G01X1152700Y1216213D02*
X1272671D01*
G01X1273238Y1223062D02*
X1152800D01*
G01X1257400Y1260100D02*
X1184000D01*
G01X1258200Y1266100D02*
X1181400D01*
G01X1149700Y1310000D02*
X1144000D01*
G01X1164174Y1324474D02*
X1149700Y1310000D01*
G01X1377133Y1324474D02*
X1164174D01*
G01X1168227Y1346900D02*
X1740000D01*
G01X1146401Y1368726D02*
X1168227Y1346900D01*
G01X1146401Y1406264D02*
Y1368726D01*
G01X1141925Y1365075D02*
Y1387075D01*
G01X1164500Y1342500D02*
X1141925Y1365075D01*
G01X1497200Y1342500D02*
X1164500D01*
G01X1153001Y1371465D02*
Y1409966D01*
G01X1170966Y1353500D02*
X1153001Y1371465D01*
G01X1365551Y1353500D02*
X1170966D01*
G01X1170878Y1356700D02*
X1240276D01*
G01X1155201Y1372377D02*
X1170878Y1356700D01*
G01X1155201Y1410878D02*
Y1372377D01*
G01X1157000Y1330000D02*
X1154500Y1327500D01*
G01X1369500Y1330000D02*
X1157000D01*
G01X1144088Y1367927D02*
Y1405182D01*
G01X1167315Y1344700D02*
X1144088Y1367927D01*
G01X1842000Y1344700D02*
X1167315D01*
G01X1140000Y1363700D02*
Y1385500D01*
G01X1163037Y1340663D02*
X1140000Y1363700D01*
G01X1488146Y1340663D02*
X1163037D01*
G01X1154648Y1333237D02*
X1150911Y1329500D01*
G01X1370463Y1333237D02*
X1154648D01*
G01X1150801Y1370550D02*
Y1408654D01*
G01X1170051Y1351300D02*
X1150801Y1370550D01*
G01X1491662Y1351300D02*
X1170051D01*
G01X1148601Y1369638D02*
Y1407459D01*
G01X1169139Y1349100D02*
X1148601Y1369638D01*
G01X1624500Y1349100D02*
X1169139D01*
G01X1141925Y1387075D02*
X1137500Y1391500D01*
G01X1137163Y1428916D02*
X1155201Y1410878D01*
G01X1215012Y18575D02*
X1236776Y40339D01*
G01X1244352Y37202D02*
X1218124Y10974D01*
G01X1220875Y46928D02*
Y73928D01*
G01X1208423Y34476D02*
X1220875Y46928D01*
G01X1212500Y50398D02*
X1205028Y42926D01*
G01X1212500Y83000D02*
Y50398D01*
G01X1219200Y47622D02*
Y74622D01*
G01X1207729Y36151D02*
X1219200Y47622D01*
G01X1214318Y20250D02*
X1235101Y41033D01*
G01X1227575Y63975D02*
X1238625Y75025D01*
G01X1227575Y44152D02*
Y63975D01*
G01X1211199Y27776D02*
X1227575Y44152D01*
G01X1215850Y49010D02*
Y81510D01*
G01X1206416Y39576D02*
X1215850Y49010D01*
G01X1214175Y49704D02*
X1205722Y41251D01*
G01X1214175Y82306D02*
Y49704D01*
G01X1225900Y44846D02*
Y71670D01*
G01X1210505Y29451D02*
X1225900Y44846D01*
G01X1224225Y45540D02*
Y72364D01*
G01X1209811Y31126D02*
X1224225Y45540D01*
G01X1217525Y48316D02*
Y80816D01*
G01X1207035Y37826D02*
X1217525Y48316D01*
G01X1222550Y46234D02*
Y73058D01*
G01X1209117Y32801D02*
X1222550Y46234D01*
G01X1228672Y81725D02*
X1313480D01*
G01X1220875Y73928D02*
X1228672Y81725D01*
G01X1223833Y94333D02*
X1212500Y83000D01*
G01X1302179Y94333D02*
X1223833D01*
G01X1232211Y87633D02*
X1333557D01*
G01X1219200Y74622D02*
X1232211Y87633D01*
G01X1225323Y90983D02*
X1329014D01*
G01X1215850Y81510D02*
X1225323Y90983D01*
G01X1224527Y92658D02*
X1214175Y82306D01*
G01X1302933Y92658D02*
X1224527D01*
G01X1230930Y76700D02*
X1333575D01*
G01X1225900Y71670D02*
X1230930Y76700D01*
G01X1230236Y78375D02*
X1315433D01*
G01X1224225Y72364D02*
X1230236Y78375D01*
G01X1226017Y89308D02*
X1329709D01*
G01X1217525Y80816D02*
X1226017Y89308D01*
G01X1229542Y80050D02*
X1314175D01*
G01X1222550Y73058D02*
X1229542Y80050D01*
G01X1254723Y201377D02*
X1227983Y174637D01*
G01X1256049Y197965D02*
X1225684Y167600D01*
G01X1255355Y199640D02*
X1227115Y171400D01*
G01X1261402Y210425D02*
X1227702Y176725D01*
G01X1193877Y181242D02*
X1191835Y179200D01*
G01X1215795Y181242D02*
X1193877D01*
G01X1229443D02*
X1215795D01*
G01X1262712Y214511D02*
X1229443Y181242D01*
G01X1191453Y290900D02*
X1185588Y285035D01*
G01X1358573Y290900D02*
X1191453D01*
G01X1197897Y297100D02*
X1262075D01*
G01X1189700Y305297D02*
X1197897Y297100D01*
G01X1189700Y308527D02*
Y305297D01*
G01X1193617Y282833D02*
X1341653D01*
G01X1189996Y279212D02*
X1193617Y282833D01*
G01X1190200Y285023D02*
X1346240D01*
G01X1201835Y305319D02*
X1208657Y312141D01*
G01D02*
X1407126D01*
G01X1230615Y766464D02*
X1261361Y735718D01*
G01X1228772Y763464D02*
X1259518Y732718D01*
G01X1220317Y910817D02*
X1243200Y933700D01*
G01X1212117Y913017D02*
X1264018Y964918D01*
G01X1251231Y978262D02*
X1198424Y925455D01*
G01X1263074Y933901D02*
X1226790Y897617D01*
G01X1211205Y915217D02*
X1263106Y967118D01*
G01X1250300Y983600D02*
X1193830Y927130D01*
G01X1227965Y895417D02*
X1259808Y927260D01*
G01X1223142Y906417D02*
X1259459Y942734D01*
G01X1261282Y971518D02*
X1209381Y919617D01*
G01X1251833Y973718D02*
X1199932Y921817D01*
G01X1260371Y940534D02*
X1224054Y904217D01*
G01X1225878Y899817D02*
X1262195Y936134D01*
G01X1224966Y902017D02*
X1261283Y938334D01*
G01X1222230Y908617D02*
X1258547Y944934D01*
G01X1210293Y917417D02*
X1262194Y969318D01*
G01X1199118Y923780D02*
X1251745Y976407D01*
G01X1228988Y985293D02*
X1199907Y1014374D01*
G01X1267179Y985293D02*
X1228988D01*
G01X1231792Y990607D02*
X1203000Y1019399D01*
G01X1263618Y990607D02*
X1231792D01*
G01X1230019Y986968D02*
X1200938Y1016049D01*
G01X1271195Y986968D02*
X1230019D01*
G01X1231050Y988643D02*
X1201969Y1017724D01*
G01X1266413Y988643D02*
X1231050D01*
G01X1239900Y1025800D02*
X1211611Y1054089D01*
G01X1214271Y1081000D02*
X1275905Y1019366D01*
G01X1207651Y1106905D02*
X1283975Y1030581D01*
G01X1206267Y1104705D02*
X1282708Y1028264D01*
G01X1213164Y1056289D02*
X1266787Y1002666D01*
G01X1216812Y1065089D02*
X1270375Y1011526D01*
G01X1203995Y1102505D02*
X1252400Y1054100D01*
G01X1278619Y1023866D02*
X1217085Y1085400D01*
G01X1269523Y1009266D02*
X1215900Y1062889D01*
G01X1215998Y1073049D02*
X1274207Y1014840D01*
G01X1214609Y1070849D02*
X1256142Y1029316D01*
G01X1214988Y1060689D02*
X1268611Y1007066D01*
G01X1214076Y1058489D02*
X1267891Y1004674D01*
G01X1216910Y1075249D02*
X1275019Y1017140D01*
G01X1216173Y1083200D02*
X1277707Y1021666D01*
G01X1210388Y1113505D02*
X1286530Y1037363D01*
G01X1285618Y1035163D02*
X1209476Y1111305D01*
G01X1208564Y1109105D02*
X1284790Y1032879D01*
G01X1235101Y60856D02*
X1241744Y67499D01*
G01X1235101Y41033D02*
Y60856D01*
G01X1242438Y65824D02*
X1315908D01*
G01X1236776Y60162D02*
X1242438Y65824D01*
G01X1236776Y40339D02*
Y60162D01*
G01X1244352Y56250D02*
Y37202D01*
G01X1246351Y58249D02*
X1244352Y56250D01*
G01X1310400Y58249D02*
X1246351D01*
G01X1241744Y67499D02*
X1316602D01*
G01X1238625Y75025D02*
X1332474D01*
G01X1282416Y201377D02*
X1254723D01*
G01X1437835Y197965D02*
X1256049D01*
G01X1440004Y199640D02*
X1255355D01*
G01X1436497Y210425D02*
X1261402D01*
G01X1435134Y214511D02*
X1262712D01*
G01X1261361Y735718D02*
X1341980D01*
G01X1259518Y732718D02*
X1346240D01*
G01X1264279Y782761D02*
X1246737Y800303D01*
G01X1330239Y782761D02*
X1264279D01*
G01X1262484Y781086D02*
X1329074D01*
G01X1244942Y798628D02*
X1262484Y781086D01*
G01X1265027Y784436D02*
X1331464D01*
G01X1247197Y802266D02*
X1265027Y784436D01*
G01X1261189Y779411D02*
X1326089D01*
G01X1243647Y796953D02*
X1261189Y779411D01*
G01X1288148Y878200D02*
X1249865Y839917D01*
G01X1289060Y876000D02*
X1250777Y837717D01*
G01X1251689Y835517D02*
X1288972Y872800D01*
G01X1284540Y903000D02*
X1241257Y859717D01*
G01X1279996Y912200D02*
X1241141Y873345D01*
G01X1279084Y914400D02*
X1240229Y875545D01*
G01X1276772Y921500D02*
X1237417Y882145D01*
G01X1278296Y916800D02*
X1239241Y877745D01*
G01X1244905Y850917D02*
X1287388Y893400D01*
G01X1287236Y880400D02*
X1248953Y842117D01*
G01X1277384Y919000D02*
X1238329Y879945D01*
G01X1235025Y864117D02*
X1280908Y910000D01*
G01X1247129Y846517D02*
X1286147Y885535D01*
G01X1285764Y898000D02*
X1243081Y855317D01*
G01X1245817Y848717D02*
X1284929Y887829D01*
G01X1285052Y900400D02*
X1242169Y857517D01*
G01X1286627Y895751D02*
X1243993Y853117D01*
G01X1286424Y882700D02*
X1248041Y844317D01*
G01X1274548Y925800D02*
X1235401Y886653D01*
G01X1275460Y923600D02*
X1236205Y884345D01*
G01X1235937Y861917D02*
X1281020Y907000D01*
G01X1587400Y912200D02*
X1279996D01*
G01X1608200Y914400D02*
X1279084D01*
G01X1819541Y921500D02*
X1276772D01*
G01X1340600Y933901D02*
X1263074D01*
G01X1618200Y916800D02*
X1278296D01*
G01X1272724Y930200D02*
X1380300D01*
G01X1235741Y893217D02*
X1272724Y930200D01*
G01X1619895Y919000D02*
X1277384D01*
G01X1273636Y928000D02*
X1236653Y891017D01*
G01X1521200Y928000D02*
X1273636D01*
G01X1280908Y910000D02*
X1448000D01*
G01X1262195Y936134D02*
X1344499D01*
G01X1636400Y925800D02*
X1274548D01*
G01X1692100Y923600D02*
X1275460D01*
G01X1281020Y907000D02*
X1346076D01*
G01X1264018Y964918D02*
X1287518D01*
G01X1261283Y978262D02*
X1251231D01*
G01X1264269Y981248D02*
X1261283Y978262D01*
G01X1263106Y967118D02*
X1286654D01*
G01X1266100Y983600D02*
X1250300D01*
G01X1267500Y982200D02*
X1266100Y983600D01*
G01X1286000Y982200D02*
X1267500D01*
G01X1267859Y984613D02*
X1267179Y985293D01*
G01X1274413Y984613D02*
X1267859D01*
G01X1259459Y942734D02*
X1663266D01*
G01X1284830Y971518D02*
X1261282D01*
G01X1283918Y973718D02*
X1251833D01*
G01X1346323Y940534D02*
X1260371D01*
G01X1261283Y938334D02*
X1345411D01*
G01X1258547Y944934D02*
X1664178D01*
G01X1262194Y969318D02*
X1285742D01*
G01X1251745Y976407D02*
X1279599D01*
G01X1275905Y1019366D02*
X1602400D01*
G01X1266787Y1002666D02*
X1384800D01*
G01X1270375Y1011526D02*
X1690279D01*
G01X1263618Y990606D02*
Y990607D01*
G01X1271296Y986867D02*
X1271195Y986968D01*
G01X1679970Y1023866D02*
X1278619D01*
G01X1671422Y1009266D02*
X1269523D01*
G01X1274207Y1014840D02*
X1349829D01*
G01X1268378Y990608D02*
X1266413Y988643D01*
G01X1268611Y1007066D02*
X1580381D01*
G01X1267891Y1004674D02*
X1451774D01*
G01X1239900Y1024000D02*
Y1025800D01*
G01X1275019Y1017140D02*
X1478168D01*
G01X1277707Y1021666D02*
X1678347D01*
G01X1272755Y1137293D02*
X1272641Y1137179D01*
G01X1273884Y1217426D02*
X1400260D01*
G01X1272671Y1216213D02*
X1273884Y1217426D01*
G01X1275708Y1213026D02*
X1402084D01*
G01X1268907Y1206225D02*
X1275708Y1213026D01*
G01X1275114Y1221826D02*
X1466974D01*
G01X1273788Y1220500D02*
X1275114Y1221826D01*
G01X1275076Y1224900D02*
X1273238Y1223062D01*
G01X1388500Y1224900D02*
X1275076D01*
G01X1274796Y1215226D02*
X1401172D01*
G01X1272970Y1213400D02*
X1274796Y1215226D01*
G01X1274888Y1229912D02*
X1255700Y1249100D01*
G01X1709100Y1229912D02*
X1274888D01*
G01X1257812Y1256000D02*
X1281212Y1232600D01*
G01D02*
X1705500D01*
G01X1282187Y1235313D02*
X1257400Y1260100D01*
G01X1284587Y1239713D02*
X1258200Y1266100D01*
G01X1283675Y1237513D02*
X1258188Y1263000D01*
G01X1254800Y1269600D02*
X1254100Y1270300D01*
G01X1318264Y65837D02*
X1352346D01*
G01X1316602Y67499D02*
X1318264Y65837D01*
G01X1317569Y64162D02*
X1357162D01*
G01X1317386Y64345D02*
X1317569Y64162D01*
G01X1317386Y64346D02*
Y64345D01*
G01X1315908Y65824D02*
X1317386Y64346D01*
G01X1314812Y53837D02*
X1310400Y58249D01*
G01X1357550Y53837D02*
X1314812D01*
G01X1317572Y85817D02*
X1332597D01*
G01X1313480Y81725D02*
X1317572Y85817D01*
G01X1307998Y100152D02*
X1302179Y94333D01*
G01X1323968Y100152D02*
X1307998D01*
G01X1330066Y106250D02*
X1323968Y100152D01*
G01X1329014Y90983D02*
X1332906Y94875D01*
G01X1324297Y98112D02*
X1315961D01*
G01X1330760Y104575D02*
X1324297Y98112D01*
G01X1299569Y101329D02*
Y100639D01*
G01X1311439Y113199D02*
X1299569Y101329D01*
G01X1338318Y113199D02*
X1311439D01*
G01X1304563Y101964D02*
Y100771D01*
G01X1314123Y111524D02*
X1304563Y101964D01*
G01X1339012Y111524D02*
X1314123D01*
G01X1307875Y97600D02*
X1302933Y92658D01*
G01X1313697Y97600D02*
X1307875D01*
G01X1315148Y96149D02*
X1313697Y97600D01*
G01X1324703Y96149D02*
X1315148D01*
G01X1330131Y101577D02*
X1324703Y96149D01*
G01X1319223Y82165D02*
X1330866D01*
G01X1315433Y78375D02*
X1319223Y82165D01*
G01X1329709Y89308D02*
X1330689Y90288D01*
G01X1318266Y84142D02*
X1331258D01*
G01X1315155Y81031D02*
X1318266Y84142D01*
G01X1315155Y81030D02*
Y81031D01*
G01X1314175Y80050D02*
X1315155Y81030D01*
G01X1285991Y204952D02*
X1282416Y201377D01*
G01X1437718Y204952D02*
X1285991D01*
G01X1329074Y781086D02*
X1334329Y775831D01*
G01X1326089Y779411D02*
X1334300Y771200D01*
G01X1442900Y878200D02*
X1288148D01*
G01X1444400Y876000D02*
X1289060D01*
G01X1441900Y880400D02*
X1287236D01*
G01X1286147Y885535D02*
X1312767D01*
G01X1284929Y887829D02*
X1391222D01*
G01X1435300Y882700D02*
X1286424D01*
G01X1288972Y872800D02*
X1445600D01*
G01X1811820Y903000D02*
X1284540D01*
G01X1287388Y893400D02*
X1440400D01*
G01X1704010Y898000D02*
X1285764D01*
G01X1810119Y900400D02*
X1285052D01*
G01X1584751Y895751D02*
X1286627D01*
G01X1294700Y972100D02*
X1378100D01*
G01X1287518Y964918D02*
X1294700Y972100D01*
G01X1294036Y974500D02*
X1497073D01*
G01X1286654Y967118D02*
X1294036Y974500D01*
G01X1292212Y978900D02*
X1284830Y971518D01*
G01X1609773Y978900D02*
X1292212D01*
G01X1291300Y981100D02*
X1283918Y973718D01*
G01X1623173Y981100D02*
X1291300D01*
G01X1293124Y976700D02*
X1574576D01*
G01X1285742Y969318D02*
X1293124Y976700D01*
G01X1283975Y1030581D02*
X1481448D01*
G01X1282708Y1028264D02*
X1365537D01*
G01X1284790Y1032879D02*
X1620006D01*
G01X1286530Y1037363D02*
X1861046D01*
G01X1691771Y1035163D02*
X1285618D01*
G01X1612213Y1235313D02*
X1282187D01*
G01X1353546Y1239713D02*
X1284587D01*
G01X1468336Y1237513D02*
X1283675D01*
G01X1352346Y65837D02*
X1353963Y67454D01*
G01Y67456D02*
X1356463Y69956D01*
G01X1357162Y64162D02*
X1359350Y66350D01*
G01X1370300Y66587D02*
X1357550Y53837D01*
G01X1370300Y95593D02*
Y66587D01*
G01X1332597Y85817D02*
X1333281Y85133D01*
G01X1336879Y106250D02*
X1330066D01*
G01X1338215Y107586D02*
X1336879Y106250D01*
G01X1336034Y85156D02*
Y82542D01*
G01X1333557Y87633D02*
X1336034Y85156D01*
G01X1349271Y85472D02*
X1343521D01*
G01X1356463Y78280D02*
X1349271Y85472D01*
G01X1356463Y69956D02*
Y78280D01*
G01X1353963Y67454D02*
Y67456D01*
G01X1336079Y73929D02*
X1340961Y78811D01*
G01X1333570Y73929D02*
X1336079D01*
G01X1332474Y75025D02*
X1333570Y73929D01*
G01X1341145Y94875D02*
X1347607Y101337D01*
G01X1332906Y94875D02*
X1341145D01*
G01X1338014Y104575D02*
X1330760D01*
G01X1346099Y112660D02*
X1338014Y104575D01*
G01X1365439Y112660D02*
X1346099D01*
G01X1388830Y136051D02*
X1365439Y112660D01*
G01X1341129Y116010D02*
X1338318Y113199D01*
G01X1395965Y121258D02*
X1370300Y95593D01*
G01X1341823Y114335D02*
X1339012Y111524D01*
G01X1364745Y114335D02*
X1341823D01*
G01X1388136Y137726D02*
X1364745Y114335D01*
G01X1334303Y101577D02*
X1330131D01*
G01X1334304Y101576D02*
X1334303Y101577D01*
G01X1340625Y101576D02*
X1334304D01*
G01X1347564Y108515D02*
X1340625Y101576D01*
G01X1363663Y108515D02*
X1347564D01*
G01X1389524Y134376D02*
X1363663Y108515D01*
G01X1333575Y76700D02*
X1334383Y75892D01*
G01X1341877Y80671D02*
X1346081D01*
G01X1341774Y80774D02*
X1341877Y80671D01*
G01X1340064Y80774D02*
X1341774D01*
G01X1338194Y78904D02*
X1340064Y80774D01*
G01X1334127Y78904D02*
X1338194D01*
G01X1330866Y82165D02*
X1334127Y78904D01*
G01X1361786Y84919D02*
X1358355Y81488D01*
G01X1361786Y98420D02*
Y84919D01*
G01X1392375Y129009D02*
X1361786Y98420D01*
G01X1343827Y93200D02*
X1352351Y101724D01*
G01X1333600Y93200D02*
X1343827D01*
G01X1330689Y90289D02*
X1333600Y93200D01*
G01X1330689Y90288D02*
Y90289D01*
G01X1340247Y83326D02*
X1348641D01*
G01X1337500Y80579D02*
X1340247Y83326D01*
G01X1334821Y80579D02*
X1337500D01*
G01X1332541Y82859D02*
X1334821Y80579D01*
G01X1332541Y82860D02*
Y82859D01*
G01X1331561Y83840D02*
X1332541Y82860D01*
G01X1331560Y83840D02*
X1331561D01*
G01X1331258Y84142D02*
X1331560Y83840D01*
G01X1387274Y146534D02*
X1364017Y123277D01*
G01X1338400Y128380D02*
Y126015D01*
G01X1343535Y133515D02*
X1338400Y128380D01*
G01X1343535Y141492D02*
Y133515D01*
G01X1363263Y161220D02*
X1343535Y141492D01*
G01X1389979Y161220D02*
X1363263D01*
G01X1369399Y157829D02*
X1349931Y138361D01*
G01X1388957Y157829D02*
X1369399D01*
G01X1364051Y116010D02*
X1341129D01*
G01X1387442Y139401D02*
X1364051Y116010D01*
G01X1371975Y272575D02*
X1372274Y272874D01*
G01X1351911Y272575D02*
X1371975D01*
G01X1341653Y282833D02*
X1351911Y272575D01*
G01X1346240Y285023D02*
X1355991Y275272D01*
G01X1375700Y413400D02*
X1367775Y421325D01*
G01X1341980Y735718D02*
X1344062Y737800D01*
G01X1346240Y732718D02*
X1347600Y734078D01*
G01X1336292Y776708D02*
X1330239Y782761D01*
G01X1336292Y773908D02*
Y776708D01*
G01X1338700Y771500D02*
X1336292Y773908D01*
G01X1338729Y777171D02*
Y776131D01*
G01X1331464Y784436D02*
X1338729Y777171D01*
G01X1341219Y933282D02*
X1340600Y933901D01*
G01X1350057Y936800D02*
X1346323Y940534D01*
G01X1633100Y936800D02*
X1350057D01*
G01X1348233Y932400D02*
X1391000D01*
G01X1344499Y936134D02*
X1348233Y932400D01*
G01X1349145Y934600D02*
X1393800D01*
G01X1345411Y938334D02*
X1349145Y934600D01*
G01X1346076Y907000D02*
X1346080Y907004D01*
G01X1365537Y1028264D02*
X1365551Y1028250D01*
G01X1355733Y1241900D02*
X1353546Y1239713D01*
G01X1381800Y1329141D02*
X1377133Y1324474D01*
G01X1369600Y1330100D02*
X1369500Y1330000D01*
G01X1373700D02*
X1370463Y1333237D01*
G01X1402400Y103506D02*
Y119887D01*
G01X1405315Y100591D02*
X1402400Y103506D01*
G01X1423600Y99629D02*
Y119779D01*
G01X1426575Y96654D02*
X1423600Y99629D01*
G01X1415584Y114495D02*
X1414770Y115309D01*
G01X1415584Y103299D02*
Y114495D01*
G01X1418292Y100591D02*
X1415584Y103299D01*
G01X1419488Y100591D02*
X1418292D01*
G01X1414770Y115309D02*
Y122129D01*
G01X1408781Y146534D02*
X1387274D01*
G01X1411292Y149045D02*
X1408781Y146534D01*
G01X1428877Y149045D02*
X1411292D01*
G01X1397398Y168639D02*
X1389979Y161220D01*
G01X1394083Y162955D02*
X1388957Y157829D01*
G01X1424473Y162955D02*
X1394083D01*
G01X1431799Y155629D02*
X1424473Y162955D01*
G01X1414394Y136051D02*
X1388830D01*
G01X1428838Y121607D02*
X1414394Y136051D01*
G01X1421447Y139401D02*
X1387442D01*
G01X1438485Y122363D02*
X1421447Y139401D01*
G01X1395965Y121607D02*
Y121258D01*
G01X1397291Y122933D02*
X1395965Y121607D01*
G01X1399354Y122933D02*
X1397291D01*
G01X1402400Y119887D02*
X1399354Y122933D01*
G01X1420399Y137726D02*
X1388136D01*
G01X1436554Y121571D02*
X1420399Y137726D01*
G01X1409003Y134376D02*
X1389524D01*
G01X1423600Y119779D02*
X1409003Y134376D01*
G01X1407139Y129009D02*
X1392375D01*
G01X1412706Y123442D02*
X1407139Y129009D01*
G01X1413457Y123442D02*
X1412706D01*
G01X1414770Y122129D02*
X1413457Y123442D01*
G01X1405355Y168639D02*
X1397398D01*
G01X1409364Y164630D02*
X1405355Y168639D01*
G01X1420995Y164630D02*
X1409364D01*
G01X1423397Y167032D02*
X1420995Y164630D01*
G01X1427663Y167032D02*
X1423397D01*
G01X1407126Y312141D02*
X1426915Y331930D01*
G01X1391222Y887829D02*
X1392355Y886696D01*
G01X1398000Y930400D02*
X1505900D01*
G01X1393800Y934600D02*
X1398000Y930400D01*
G01X1400399Y1217565D02*
X1558511D01*
G01X1400260Y1217426D02*
X1400399Y1217565D01*
G01X1402223Y1213165D02*
X1755439D01*
G01X1402084Y1213026D02*
X1402223Y1213165D01*
G01X1401311Y1215365D02*
X1702773D01*
G01X1401172Y1215226D02*
X1401311Y1215365D01*
G01X1381800Y1329600D02*
Y1329141D01*
G01X1445275Y108663D02*
Y132647D01*
G01X1447835Y106103D02*
X1445275Y108663D01*
G01X1433661Y114764D02*
X1428838Y119587D01*
G01X1436554Y115021D02*
Y121571D01*
G01X1440748Y110827D02*
X1436554Y115021D01*
G01X1508200Y127600D02*
X1437835Y197965D01*
G01X1445275Y132647D02*
X1428877Y149045D01*
G01X1469253Y155629D02*
X1431799D01*
G01X1502010Y122872D02*
X1469253Y155629D01*
G01X1428838Y119587D02*
Y121607D01*
G01X1438485Y118602D02*
Y122363D01*
G01X1440748Y116339D02*
X1438485Y118602D01*
G01X1516152Y126518D02*
X1437718Y204952D01*
G01X1514227Y125417D02*
X1440004Y199640D01*
G01X1520964Y125958D02*
X1436497Y210425D01*
G01X1522889Y126756D02*
X1435134Y214511D01*
G01X1426915Y354317D02*
X1431909Y359311D01*
G01X1426915Y331930D02*
Y354317D01*
G01X1451000Y886300D02*
X1442900Y878200D01*
G01X1636189Y886300D02*
X1451000D01*
G01X1452600Y884200D02*
X1444400Y876000D01*
G01X1640089Y884200D02*
X1452600D01*
G01X1449900Y888400D02*
X1441900Y880400D01*
G01X1570500Y888400D02*
X1449900D01*
G01X1455300Y882500D02*
X1644258D01*
G01X1445600Y872800D02*
X1455300Y882500D01*
G01X1440400Y893400D02*
X1440500Y893500D01*
G01X1451774Y1004674D02*
X1451800Y1004700D01*
G01X1466974Y1221826D02*
X1467000Y1221800D01*
G01X1473600Y1242777D02*
X1468336Y1237513D01*
G01X1516152Y108652D02*
Y126518D01*
G01X1518701Y106103D02*
X1516152Y108652D01*
G01X1508200Y105580D02*
Y127600D01*
G01X1511614Y102166D02*
X1508200Y105580D01*
G01X1502010Y108621D02*
Y122872D01*
G01X1504528Y106103D02*
X1502010Y108621D01*
G01X1514227Y105065D02*
Y125417D01*
G01X1518701Y100591D02*
X1514227Y105065D01*
G01X1518701Y114764D02*
X1522889Y118952D01*
G01X1520964Y122539D02*
Y125958D01*
G01X1518701Y120276D02*
X1520964Y122539D01*
G01X1522889Y118952D02*
Y126756D01*
G01X1497073Y974500D02*
X1503394Y968179D01*
G01X1481448Y1030581D02*
X1481529Y1030500D01*
G01X1478168Y1017140D02*
X1478194Y1017166D01*
G01X1488409Y1340400D02*
X1488146Y1340663D01*
G01X1500200Y1340400D02*
X1488409D01*
G01X1501600Y1341800D02*
X1500200Y1340400D01*
G01X1501600Y1342300D02*
Y1341800D01*
G01X1558511Y1217565D02*
X1558650Y1217426D01*
G01X1621787Y917108D02*
X1619895Y919000D01*
G01X1584800Y895800D02*
X1584751Y895751D01*
G01X1615494Y973179D02*
X1609773Y978900D01*
G01X1613400Y1236500D02*
X1612213Y1235313D01*
G01X1639644Y889755D02*
X1636189Y886300D01*
G01X1643344Y887455D02*
X1640089Y884200D01*
G01X1644258Y882500D02*
X1646013Y884255D01*
G01X1633600Y936300D02*
X1633100Y936800D01*
G01X1663266Y942734D02*
X1675000Y931000D01*
G01X1629094Y975179D02*
X1623173Y981100D01*
G01X1664178Y944934D02*
X1675612Y933500D01*
G01X1620006Y1032879D02*
X1620059Y1032932D01*
G01X1675000Y931000D02*
X1750200D01*
G01X1675612Y933500D02*
X1807757D01*
G01X1674934Y961857D02*
X1674814Y961977D01*
G01X1726269Y961857D02*
X1674934D01*
G01X1677056Y954636D02*
X1783447D01*
G01X1680012Y952402D02*
X1796619D01*
G01X1680087Y1023983D02*
X1679970Y1023866D01*
G01X1678347Y1021666D02*
X1685047Y1014966D01*
G01X1686653Y1052447D02*
X1685100Y1054000D01*
G01X1801147Y1052447D02*
X1686653D01*
G01X1682828Y1039641D02*
X1856377D01*
G01X1679300Y1043169D02*
X1682828Y1039641D01*
G01X1702773Y1215365D02*
X1702838Y1215300D01*
G01X1710617Y1231429D02*
X1709100Y1229912D01*
G01X1706900Y1234000D02*
X1715049D01*
G01X1705500Y1232600D02*
X1706900Y1234000D01*
G01X1750200Y931000D02*
X1752000Y929200D01*
G01X1733484Y969072D02*
X1726269Y961857D01*
G01X1752223Y969072D02*
X1733484D01*
G01X1755010Y966285D02*
X1752223Y969072D01*
G01X1755439Y1213165D02*
X1755900Y1212704D01*
G01X1823937Y890883D02*
X1811820Y903000D01*
G01X1824170Y886349D02*
X1810119Y900400D01*
G01X1807757Y933500D02*
X1813851Y927406D01*
G01X1783447Y954636D02*
X1797463Y968652D01*
G01X1796619Y952402D02*
X1806077Y961860D01*
G01X1810900Y1062200D02*
X1801147Y1052447D01*
G01X1810900Y1070073D02*
Y1062200D01*
G01X1812050Y1071223D02*
X1810900Y1070073D01*
G01X1861046Y1037363D02*
X1864617Y1040934D01*
G01X1856377Y1039641D02*
X1872162Y1055426D01*
M02*
